FILE_TYPE = MACRO_DRAWING;
SET COLOR_WIRE YELLOW;
SET COLOR_PROP ORANGE;
SET COLOR_DOT WHITE;
SET COLOR_ARC YELLOW;
SET COLOR_BODY GREEN;
SET COLOR_NOTE PURPLE;
SET PROP_DISPLAY VALUE;
SET PAGE_NUMBER P199;
FORCEADD VCC_CORE..1
(-7625 950);
FORCEPROP 3 LASTPIN (-7625 900) SIG_NAME P5V_AUX\g
J 0
(-7615 910);
DISPLAY 0.659574 (-7615 910);
PAINT MONO (-7615 910);
DISPLAY INVISIBLE (-7615 910);
FORCEPROP 1 LAST HDL_POWER P5V_AUX
J 1
(-7625 1000);
DISPLAY 0.489362 (-7625 1000);
PAINT GREEN (-7625 1000);
FORCEPROP 2 LAST CDS_LIB pure_quanta_power
J 0
(-7625 950);
DISPLAY INVISIBLE (-7625 950);
FORCEPROP 1 LAST PATH I1
J 0
(-7575 975);
DISPLAY 0.872340 (-7575 975);
PAINT AQUA (-7575 975);
DISPLAY INVISIBLE (-7575 975);
FORCEADD OFFPAGE..4
R 2
(-7550 3825);
FORCEPROP 2 LAST $XR1 217 
J 0
(-7891 3825);
DISPLAY 0.638298 (-7891 3825);
PAINT MONO (-7891 3825);
FORCEPROP 2 LAST $XR0 54 
J 0
(-7771 3825);
DISPLAY 0.638298 (-7771 3825);
PAINT MONO (-7771 3825);
FORCEPROP 2 LAST CDS_LIB standard
J 0
(-7550 3825);
DISPLAY INVISIBLE (-7550 3825);
FORCEPROP 1 LAST OFFPAGE TRUE
J 2
(-7875 3700);
DISPLAY 0.872340 (-7875 3700);
PAINT GREEN (-7875 3700);
DISPLAY INVISIBLE (-7875 3700);
FORCEPROP 1 LAST COMMENT_BODY TRUE
J 2
(-7525 3725);
DISPLAY 0.872340 (-7525 3725);
PAINT GREEN (-7525 3725);
DISPLAY INVISIBLE (-7525 3725);
FORCEPROP 2 LAST PATH I10
J 0
(-7875 3875);
DISPLAY 0.680851 (-7875 3875);
DISPLAY INVISIBLE (-7875 3875);
FORCEADD OFFPAGE..4
R 2
(-7550 4075);
FORCEPROP 2 LAST $XR0 54 
J 0
(-7771 4075);
DISPLAY 0.638298 (-7771 4075);
PAINT MONO (-7771 4075);
FORCEPROP 2 LAST CDS_LIB standard
J 2
(-7550 4075);
DISPLAY INVISIBLE (-7550 4075);
FORCEPROP 1 LAST OFFPAGE TRUE
J 2
(-7875 3950);
DISPLAY 0.872340 (-7875 3950);
PAINT GREEN (-7875 3950);
DISPLAY INVISIBLE (-7875 3950);
FORCEPROP 1 LAST COMMENT_BODY TRUE
J 2
(-7525 3975);
DISPLAY 0.872340 (-7525 3975);
PAINT GREEN (-7525 3975);
DISPLAY INVISIBLE (-7525 3975);
FORCEPROP 2 LAST PATH I11
J 0
(-7875 4125);
DISPLAY 0.680851 (-7875 4125);
DISPLAY INVISIBLE (-7875 4125);
FORCEADD OFFPAGE..2
R 2
(-7000 2125);
FORCEPROP 2 LAST $XR0 82 
J 0
(-7224 2125);
DISPLAY 0.638298 (-7224 2125);
PAINT MONO (-7224 2125);
FORCEPROP 2 LAST CDS_LIB standard
J 0
(-7000 2125);
DISPLAY INVISIBLE (-7000 2125);
FORCEPROP 1 LAST OFFPAGE TRUE
J 2
(-7325 2000);
DISPLAY 0.872340 (-7325 2000);
PAINT GREEN (-7325 2000);
DISPLAY INVISIBLE (-7325 2000);
FORCEPROP 1 LAST COMMENT_BODY TRUE
J 2
(-6955 2030);
DISPLAY 0.872340 (-6955 2030);
PAINT GREEN (-6955 2030);
DISPLAY INVISIBLE (-6955 2030);
FORCEPROP 2 LAST PATH I12
J 0
(-7250 2175);
DISPLAY 0.680851 (-7250 2175);
DISPLAY INVISIBLE (-7250 2175);
FORCEADD Q_RES..1
(-6250 2125);
FORCEPROP 1 LAST LOCATION R8010
J 0
(-6300 2175);
DISPLAY 0.489362 (-6300 2175);
PAINT SKYBLUE (-6300 2175);
FORCEPROP 0 LAST $SEC 1
J 0
(-6300 2225);
DISPLAY 0.680851 (-6300 2225);
PAINT MONO (-6300 2225);
DISPLAY INVISIBLE (-6300 2225);
FORCEPROP 0 LAST CDS_SEC 1
J 0
(-6300 2225);
DISPLAY 1.021277 (-6300 2225);
DISPLAY INVISIBLE (-6300 2225);
FORCEPROP 1 LASTPIN (-6350 2125) $PN 1
J 0
(-6338 2137);
DISPLAY 0.489362 (-6338 2137);
PAINT MONO (-6338 2137);
FORCEPROP 1 LASTPIN (-6150 2125) $PN 2
J 0
(-6188 2137);
DISPLAY 0.489362 (-6188 2137);
PAINT MONO (-6188 2137);
FORCEPROP 1 LAST WATTAGE 1/16W
J 0
(-6150 2075);
DISPLAY 0.489362 (-6150 2075);
PAINT SKYBLUE (-6150 2075);
FORCEPROP 1 LAST VALUE 0
J 2
(-6375 2150);
DISPLAY 0.489362 (-6375 2150);
PAINT SKYBLUE (-6375 2150);
FORCEPROP 1 LAST TOLERANCE 5%
J 0
(-6125 2150);
DISPLAY 0.489362 (-6125 2150);
PAINT SKYBLUE (-6125 2150);
FORCEPROP 1 LAST PACK_TYPE 0402LF
J 0
(-6150 2050);
DISPLAY 0.489362 (-6150 2050);
PAINT SKYBLUE (-6150 2050);
FORCEPROP 1 LAST MATERIAL EMPTY
J 0
(-6500 2050);
DISPLAY 0.489362 (-6500 2050);
PAINT RED (-6500 2050);
FORCEPROP 2 LAST CDS_LIB pure_quanta
J 0
(-6250 2125);
DISPLAY INVISIBLE (-6250 2125);
FORCEPROP 1 LAST PATH I13
J 0
(-6300 2275);
DISPLAY 0.978723 (-6300 2275);
PAINT WHITE (-6300 2275);
DISPLAY INVISIBLE (-6300 2275);
FORCEPROP 1 LAST PART_NUMBER CS00002JB13
J 0
(-6500 2075);
DISPLAY 0.489362 (-6500 2075);
PAINT SKYBLUE (-6500 2075);
DISPLAY INVISIBLE (-6500 2075);
FORCEADD UNIVERSAL_GND..1
(-6750 3500);
FORCEPROP 3 LASTPIN (-6750 3550) SIG_NAME GND\g
J 0
(-6740 3560);
DISPLAY 0.659574 (-6740 3560);
PAINT MONO (-6740 3560);
DISPLAY INVISIBLE (-6740 3560);
FORCEPROP 2 LAST CDS_LIB pure_quanta_power
J 0
(-6750 3500);
DISPLAY INVISIBLE (-6750 3500);
FORCEPROP 1 LAST HDL_POWER GND
J 1
(-6725 3425);
DISPLAY 0.872340 (-6725 3425);
PAINT GREEN (-6725 3425);
DISPLAY INVISIBLE (-6725 3425);
FORCEPROP 1 LAST PATH I14
J 0
(-6675 3500);
DISPLAY 0.872340 (-6675 3500);
PAINT AQUA (-6675 3500);
DISPLAY INVISIBLE (-6675 3500);
FORCEADD Q_RES..2
(-6750 3675);
FORCEPROP 1 LAST LOCATION PR288
J 0
(-6705 3800);
DISPLAY 0.489362 (-6705 3800);
PAINT SKYBLUE (-6705 3800);
FORCEPROP 0 LAST $SEC 1
J 0
(-6700 3850);
DISPLAY 0.680851 (-6700 3850);
PAINT MONO (-6700 3850);
DISPLAY INVISIBLE (-6700 3850);
FORCEPROP 0 LAST CDS_SEC 1
J 0
(-6700 3850);
DISPLAY 1.021277 (-6700 3850);
DISPLAY INVISIBLE (-6700 3850);
FORCEPROP 1 LASTPIN (-6750 3775) $PN 1
J 0
(-6745 3737);
DISPLAY 0.489362 (-6745 3737);
PAINT MONO (-6745 3737);
FORCEPROP 1 LASTPIN (-6750 3575) $PN 2
J 0
(-6745 3585);
DISPLAY 0.489362 (-6745 3585);
PAINT MONO (-6745 3585);
FORCEPROP 1 LAST MATERIAL CHIP
J 0
(-6700 3600);
DISPLAY 0.489362 (-6700 3600);
PAINT SKYBLUE (-6700 3600);
FORCEPROP 1 LAST TOLERANCE 1%
J 0
(-6700 3700);
DISPLAY 0.489362 (-6700 3700);
PAINT SKYBLUE (-6700 3700);
FORCEPROP 1 LAST VALUE 49.9
J 0
(-6700 3750);
DISPLAY 0.489362 (-6700 3750);
PAINT SKYBLUE (-6700 3750);
FORCEPROP 1 LAST WATTAGE 1/16W
J 0
(-6700 3650);
DISPLAY 0.489362 (-6700 3650);
PAINT SKYBLUE (-6700 3650);
FORCEPROP 1 LAST PACK_TYPE 0402LF
J 0
(-6700 3500);
DISPLAY 0.489362 (-6700 3500);
PAINT SKYBLUE (-6700 3500);
FORCEPROP 2 LAST CDS_LIB pure_quanta
J 0
(-6750 3675);
DISPLAY INVISIBLE (-6750 3675);
FORCEPROP 1 LAST PATH I15
J 0
(-6700 3850);
DISPLAY 0.978723 (-6700 3850);
PAINT WHITE (-6700 3850);
DISPLAY INVISIBLE (-6700 3850);
FORCEPROP 1 LAST PART_NUMBER CS04992FB07
J 0
(-6700 3550);
DISPLAY 0.489362 (-6700 3550);
PAINT SKYBLUE (-6700 3550);
DISPLAY INVISIBLE (-6700 3550);
FORCEADD UNIVERSAL_GND..1
(-5725 275);
FORCEPROP 3 LASTPIN (-5725 325) SIG_NAME GND\g
J 0
(-5715 335);
DISPLAY 0.659574 (-5715 335);
PAINT MONO (-5715 335);
DISPLAY INVISIBLE (-5715 335);
FORCEPROP 2 LAST CDS_LIB pure_quanta_power
J 0
(-5725 275);
DISPLAY INVISIBLE (-5725 275);
FORCEPROP 1 LAST HDL_POWER GND
J 1
(-5700 200);
DISPLAY 0.872340 (-5700 200);
PAINT GREEN (-5700 200);
DISPLAY INVISIBLE (-5700 200);
FORCEPROP 1 LAST PATH I16
J 0
(-5650 275);
DISPLAY 0.872340 (-5650 275);
PAINT AQUA (-5650 275);
DISPLAY INVISIBLE (-5650 275);
FORCEADD Q_RES..2
(-5725 475);
FORCEPROP 1 LAST LOCATION PR604
J 0
(-5675 600);
DISPLAY 0.489362 (-5675 600);
PAINT SKYBLUE (-5675 600);
FORCEPROP 0 LAST $SEC 1
J 0
(-5675 625);
DISPLAY 0.680851 (-5675 625);
PAINT MONO (-5675 625);
DISPLAY INVISIBLE (-5675 625);
FORCEPROP 0 LAST CDS_SEC 1
J 0
(-5675 625);
DISPLAY 0.680851 (-5675 625);
DISPLAY INVISIBLE (-5675 625);
FORCEPROP 1 LASTPIN (-5725 575) $PN 1
J 0
(-5720 537);
DISPLAY 0.787234 (-5720 537);
PAINT MONO (-5720 537);
DISPLAY INVISIBLE (-5720 537);
FORCEPROP 1 LASTPIN (-5725 375) $PN 2
J 0
(-5720 385);
DISPLAY 0.787234 (-5720 385);
PAINT MONO (-5720 385);
DISPLAY INVISIBLE (-5720 385);
FORCEPROP 1 LAST TOLERANCE 1%
J 0
(-5675 500);
DISPLAY 0.489362 (-5675 500);
PAINT SKYBLUE (-5675 500);
FORCEPROP 1 LAST VALUE 4.99K
J 0
(-5675 550);
DISPLAY 0.489362 (-5675 550);
PAINT SKYBLUE (-5675 550);
FORCEPROP 1 LAST WATTAGE 1/16W
J 0
(-5675 450);
DISPLAY 0.489362 (-5675 450);
PAINT SKYBLUE (-5675 450);
FORCEPROP 1 LAST MATERIAL EMPTY
J 0
(-5675 400);
DISPLAY 0.489362 (-5675 400);
PAINT RED (-5675 400);
FORCEPROP 1 LAST PACK_TYPE 0402LF
J 0
(-5675 300);
DISPLAY 0.489362 (-5675 300);
PAINT SKYBLUE (-5675 300);
FORCEPROP 2 LAST CDS_LIB pure_quanta
J 0
(-5725 475);
DISPLAY INVISIBLE (-5725 475);
FORCEPROP 1 LAST PATH I17
J 0
(-5675 650);
DISPLAY 0.978723 (-5675 650);
PAINT WHITE (-5675 650);
DISPLAY INVISIBLE (-5675 650);
FORCEPROP 1 LAST PART_NUMBER CS24992FB07
J 0
(-5675 350);
DISPLAY 0.489362 (-5675 350);
PAINT SKYBLUE (-5675 350);
DISPLAY INVISIBLE (-5675 350);
FORCEADD Q_RES..1
(-6050 675);
FORCEPROP 1 LAST LOCATION PR388
J 0
(-6075 725);
DISPLAY 0.489362 (-6075 725);
PAINT SKYBLUE (-6075 725);
FORCEPROP 0 LAST $SEC 1
J 0
(-6100 775);
DISPLAY 0.680851 (-6100 775);
PAINT MONO (-6100 775);
DISPLAY INVISIBLE (-6100 775);
FORCEPROP 0 LAST CDS_SEC 1
J 0
(-6100 775);
DISPLAY 1.021277 (-6100 775);
DISPLAY INVISIBLE (-6100 775);
FORCEPROP 1 LASTPIN (-6150 675) $PN 1
J 0
(-6138 687);
DISPLAY 0.489362 (-6138 687);
PAINT MONO (-6138 687);
FORCEPROP 1 LASTPIN (-5950 675) $PN 2
J 0
(-5988 687);
DISPLAY 0.489362 (-5988 687);
PAINT MONO (-5988 687);
FORCEPROP 1 LAST WATTAGE 1/16W
J 0
(-5950 625);
DISPLAY 0.489362 (-5950 625);
PAINT SKYBLUE (-5950 625);
FORCEPROP 1 LAST MATERIAL CHIP
J 0
(-6300 600);
DISPLAY 0.489362 (-6300 600);
PAINT SKYBLUE (-6300 600);
FORCEPROP 1 LAST VALUE 0
J 2
(-6175 700);
DISPLAY 0.489362 (-6175 700);
PAINT SKYBLUE (-6175 700);
FORCEPROP 1 LAST PACK_TYPE 0402LF
J 0
(-5950 600);
DISPLAY 0.489362 (-5950 600);
PAINT SKYBLUE (-5950 600);
FORCEPROP 1 LAST TOLERANCE 5%
J 0
(-5925 700);
DISPLAY 0.489362 (-5925 700);
PAINT SKYBLUE (-5925 700);
FORCEPROP 2 LAST CDS_LIB pure_quanta
J 0
(-6050 675);
DISPLAY INVISIBLE (-6050 675);
FORCEPROP 1 LAST PATH I18
J 0
(-6100 825);
DISPLAY 0.978723 (-6100 825);
PAINT WHITE (-6100 825);
DISPLAY INVISIBLE (-6100 825);
FORCEPROP 1 LAST PART_NUMBER CS00002JB13
J 0
(-6300 625);
DISPLAY 0.489362 (-6300 625);
PAINT SKYBLUE (-6300 625);
DISPLAY INVISIBLE (-6300 625);
FORCEADD UNIVERSAL_GND..1
(-5400 275);
FORCEPROP 3 LASTPIN (-5400 325) SIG_NAME GND\g
J 0
(-5390 335);
DISPLAY 0.659574 (-5390 335);
PAINT MONO (-5390 335);
DISPLAY INVISIBLE (-5390 335);
FORCEPROP 2 LAST CDS_LIB pure_quanta_power
J 0
(-5400 275);
DISPLAY INVISIBLE (-5400 275);
FORCEPROP 1 LAST HDL_POWER GND
J 1
(-5375 200);
DISPLAY 0.872340 (-5375 200);
PAINT GREEN (-5375 200);
DISPLAY INVISIBLE (-5375 200);
FORCEPROP 1 LAST PATH I19
J 0
(-5325 275);
DISPLAY 0.872340 (-5325 275);
PAINT AQUA (-5325 275);
DISPLAY INVISIBLE (-5325 275);
FORCEADD Q_RES..1
(-7275 850);
FORCEPROP 1 LAST LOCATION PR376
J 0
(-7325 900);
DISPLAY 0.489362 (-7325 900);
PAINT SKYBLUE (-7325 900);
FORCEPROP 0 LAST $SEC 1
J 0
(-7325 950);
DISPLAY 0.680851 (-7325 950);
PAINT MONO (-7325 950);
DISPLAY INVISIBLE (-7325 950);
FORCEPROP 0 LAST CDS_SEC 1
J 0
(-7325 950);
DISPLAY 1.021277 (-7325 950);
DISPLAY INVISIBLE (-7325 950);
FORCEPROP 1 LASTPIN (-7375 850) $PN 1
J 0
(-7363 862);
DISPLAY 0.489362 (-7363 862);
PAINT MONO (-7363 862);
FORCEPROP 1 LASTPIN (-7175 850) $PN 2
J 0
(-7213 862);
DISPLAY 0.489362 (-7213 862);
PAINT MONO (-7213 862);
FORCEPROP 1 LAST MATERIAL CHIP
J 0
(-7575 775);
DISPLAY 0.489362 (-7575 775);
PAINT SKYBLUE (-7575 775);
FORCEPROP 1 LAST VALUE 40.2K
J 2
(-7425 875);
DISPLAY 0.489362 (-7425 875);
PAINT SKYBLUE (-7425 875);
FORCEPROP 1 LAST PACK_TYPE 0402LF
J 0
(-7150 775);
DISPLAY 0.489362 (-7150 775);
PAINT SKYBLUE (-7150 775);
FORCEPROP 1 LAST TOLERANCE 1%
J 0
(-7125 875);
DISPLAY 0.489362 (-7125 875);
PAINT SKYBLUE (-7125 875);
FORCEPROP 1 LAST WATTAGE 1/16W
J 0
(-7150 800);
DISPLAY 0.489362 (-7150 800);
PAINT SKYBLUE (-7150 800);
FORCEPROP 2 LAST CDS_LIB pure_quanta
J 0
(-7275 850);
DISPLAY INVISIBLE (-7275 850);
FORCEPROP 1 LAST PATH I2
J 0
(-7325 1000);
DISPLAY 0.978723 (-7325 1000);
PAINT WHITE (-7325 1000);
DISPLAY INVISIBLE (-7325 1000);
FORCEPROP 1 LAST PART_NUMBER CS34022FB04
J 0
(-7575 800);
DISPLAY 0.489362 (-7575 800);
PAINT SKYBLUE (-7575 800);
DISPLAY INVISIBLE (-7575 800);
FORCEADD Q_CAP..1
(-5400 500);
FORCEPROP 1 LAST LOCATION PC8
J 0
(-5350 600);
DISPLAY 0.489362 (-5350 600);
PAINT SKYBLUE (-5350 600);
FORCEPROP 2 LAST SEC 1
J 0
(-5350 700);
DISPLAY 0.680851 (-5350 700);
PAINT MONO (-5350 700);
DISPLAY INVISIBLE (-5350 700);
FORCEPROP 1 LASTPIN (-5400 600) $PN 1
J 0
(-5390 580);
DISPLAY 0.489362 (-5390 580);
PAINT MONO (-5390 580);
FORCEPROP 1 LASTPIN (-5400 400) $PN 2
J 0
(-5390 380);
DISPLAY 0.489362 (-5390 380);
PAINT MONO (-5390 380);
FORCEPROP 1 LAST PACK_TYPE 0402
J 0
(-5350 300);
DISPLAY 0.489362 (-5350 300);
PAINT SKYBLUE (-5350 300);
FORCEPROP 1 LAST VOLTAGE 25V
J 0
(-5350 500);
DISPLAY 0.489362 (-5350 500);
PAINT SKYBLUE (-5350 500);
FORCEPROP 1 LAST VALUE 0.1UF
J 0
(-5350 550);
DISPLAY 0.489362 (-5350 550);
PAINT SKYBLUE (-5350 550);
FORCEPROP 1 LAST TOLERANCE 10%
J 0
(-5350 450);
DISPLAY 0.489362 (-5350 450);
PAINT SKYBLUE (-5350 450);
FORCEPROP 1 LAST MATERIAL X7R
J 0
(-5350 400);
DISPLAY 0.489362 (-5350 400);
PAINT SKYBLUE (-5350 400);
FORCEPROP 2 LAST CDS_LIB pure_quanta
J 0
(-5400 500);
DISPLAY INVISIBLE (-5400 500);
FORCEPROP 2 LAST SEC_TYPE 0402
J 0
(-5350 700);
DISPLAY 1.021277 (-5350 700);
DISPLAY INVISIBLE (-5350 700);
FORCEPROP 1 LAST PATH I20
J 0
(-5350 650);
DISPLAY 0.978723 (-5350 650);
PAINT WHITE (-5350 650);
DISPLAY INVISIBLE (-5350 650);
FORCEPROP 1 LAST PART_NUMBER CH4104K1B00
J 0
(-5350 350);
DISPLAY 0.489362 (-5350 350);
PAINT SKYBLUE (-5350 350);
DISPLAY INVISIBLE (-5350 350);
FORCEADD UNIVERSAL_GND..1
(-6175 1150);
FORCEPROP 3 LASTPIN (-6175 1200) SIG_NAME GND\g
J 0
(-6165 1210);
DISPLAY 0.659574 (-6165 1210);
PAINT MONO (-6165 1210);
DISPLAY INVISIBLE (-6165 1210);
FORCEPROP 2 LAST CDS_LIB pure_quanta_power
J 0
(-6175 1150);
DISPLAY INVISIBLE (-6175 1150);
FORCEPROP 1 LAST HDL_POWER GND
J 1
(-6150 1075);
DISPLAY 0.872340 (-6150 1075);
PAINT GREEN (-6150 1075);
DISPLAY INVISIBLE (-6150 1075);
FORCEPROP 1 LAST PATH I21
J 0
(-6100 1150);
DISPLAY 0.872340 (-6100 1150);
PAINT AQUA (-6100 1150);
DISPLAY INVISIBLE (-6100 1150);
FORCEADD UNIVERSAL_GND..1
(-5175 475);
FORCEPROP 3 LASTPIN (-5175 525) SIG_NAME GND\g
J 0
(-5165 535);
DISPLAY 0.659574 (-5165 535);
PAINT MONO (-5165 535);
DISPLAY INVISIBLE (-5165 535);
FORCEPROP 2 LAST CDS_LIB pure_quanta_power
J 0
(-5175 475);
DISPLAY INVISIBLE (-5175 475);
FORCEPROP 1 LAST HDL_POWER GND
J 1
(-5150 400);
DISPLAY 0.872340 (-5150 400);
PAINT GREEN (-5150 400);
DISPLAY INVISIBLE (-5150 400);
FORCEPROP 1 LAST PATH I23
J 0
(-5100 475);
DISPLAY 0.872340 (-5100 475);
PAINT AQUA (-5100 475);
DISPLAY INVISIBLE (-5100 475);
FORCEADD Q_RES..2
(-5975 2350);
FORCEPROP 1 LAST LOCATION R8011
J 0
(-5930 2475);
DISPLAY 0.489362 (-5930 2475);
PAINT SKYBLUE (-5930 2475);
FORCEPROP 0 LAST $SEC 1
J 0
(-5925 2525);
DISPLAY 0.680851 (-5925 2525);
PAINT MONO (-5925 2525);
DISPLAY INVISIBLE (-5925 2525);
FORCEPROP 0 LAST CDS_SEC 1
J 0
(-5925 2525);
DISPLAY 1.021277 (-5925 2525);
DISPLAY INVISIBLE (-5925 2525);
FORCEPROP 1 LASTPIN (-5975 2450) $PN 1
J 0
(-5970 2412);
DISPLAY 0.489362 (-5970 2412);
PAINT MONO (-5970 2412);
FORCEPROP 1 LASTPIN (-5975 2250) $PN 2
J 0
(-5970 2260);
DISPLAY 0.489362 (-5970 2260);
PAINT MONO (-5970 2260);
FORCEPROP 1 LAST WATTAGE 1/16W
J 0
(-5935 2325);
DISPLAY 0.489362 (-5935 2325);
PAINT SKYBLUE (-5935 2325);
FORCEPROP 1 LAST MATERIAL EMPTY
J 0
(-5935 2275);
DISPLAY 0.489362 (-5935 2275);
PAINT RED (-5935 2275);
FORCEPROP 1 LAST VALUE 1K
J 0
(-5930 2425);
DISPLAY 0.489362 (-5930 2425);
PAINT SKYBLUE (-5930 2425);
FORCEPROP 1 LAST TOLERANCE 1%
J 0
(-5930 2375);
DISPLAY 0.489362 (-5930 2375);
PAINT SKYBLUE (-5930 2375);
FORCEPROP 1 LAST PACK_TYPE 0402LF
J 0
(-5935 2175);
DISPLAY 0.489362 (-5935 2175);
PAINT SKYBLUE (-5935 2175);
FORCEPROP 2 LAST CDS_LIB pure_quanta
J 0
(-5975 2350);
DISPLAY INVISIBLE (-5975 2350);
FORCEPROP 1 LAST PATH I24
J 0
(-5925 2525);
DISPLAY 0.978723 (-5925 2525);
PAINT WHITE (-5925 2525);
DISPLAY INVISIBLE (-5925 2525);
FORCEPROP 1 LAST PART_NUMBER CS21002FB06
J 0
(-5935 2225);
DISPLAY 0.489362 (-5935 2225);
PAINT SKYBLUE (-5935 2225);
DISPLAY INVISIBLE (-5935 2225);
FORCEADD VCC_CORE..1
(-5975 2550);
FORCEPROP 3 LASTPIN (-5975 2500) SIG_NAME PVDD18_S5_P1\g
J 0
(-5965 2510);
DISPLAY 0.659574 (-5965 2510);
PAINT MONO (-5965 2510);
DISPLAY INVISIBLE (-5965 2510);
FORCEPROP 1 LAST HDL_POWER PVDD18_S5_P1
J 1
(-5975 2600);
DISPLAY 0.489362 (-5975 2600);
PAINT GREEN (-5975 2600);
FORCEPROP 2 LAST CDS_LIB pure_quanta_power
J 0
(-5975 2550);
DISPLAY INVISIBLE (-5975 2550);
FORCEPROP 1 LAST PATH I25
J 0
(-5925 2575);
DISPLAY 0.872340 (-5925 2575);
PAINT AQUA (-5925 2575);
DISPLAY INVISIBLE (-5925 2575);
FORCEADD UNIVERSAL_GND..1
R 2
(-5375 2575);
FORCEPROP 3 LASTPIN (-5375 2625) SIG_NAME GND\g
J 0
(-5365 2635);
DISPLAY 0.659574 (-5365 2635);
PAINT MONO (-5365 2635);
DISPLAY INVISIBLE (-5365 2635);
FORCEPROP 2 LAST CDS_LIB pure_quanta_power
J 0
(-5375 2575);
DISPLAY INVISIBLE (-5375 2575);
FORCEPROP 1 LAST HDL_POWER GND
J 1
(-5400 2500);
DISPLAY 0.872340 (-5400 2500);
PAINT GREEN (-5400 2500);
DISPLAY INVISIBLE (-5400 2500);
FORCEPROP 1 LAST PATH I26
J 2
(-5450 2575);
DISPLAY 0.872340 (-5450 2575);
PAINT AQUA (-5450 2575);
DISPLAY INVISIBLE (-5450 2575);
FORCEADD Q_RES..1
(-6050 4075);
FORCEPROP 1 LAST LOCATION PR384
J 0
(-6100 4125);
DISPLAY 0.489362 (-6100 4125);
PAINT SKYBLUE (-6100 4125);
FORCEPROP 0 LAST $SEC 1
J 0
(-6100 4150);
DISPLAY 0.680851 (-6100 4150);
PAINT MONO (-6100 4150);
DISPLAY INVISIBLE (-6100 4150);
FORCEPROP 0 LAST CDS_SEC 1
J 0
(-6100 4150);
DISPLAY 1.021277 (-6100 4150);
DISPLAY INVISIBLE (-6100 4150);
FORCEPROP 1 LASTPIN (-6150 4075) $PN 1
J 0
(-6138 4087);
DISPLAY 0.489362 (-6138 4087);
PAINT MONO (-6138 4087);
FORCEPROP 1 LASTPIN (-5950 4075) $PN 2
J 0
(-5988 4087);
DISPLAY 0.489362 (-5988 4087);
PAINT MONO (-5988 4087);
FORCEPROP 1 LAST TOLERANCE 5%
J 0
(-5925 4100);
DISPLAY 0.489362 (-5925 4100);
PAINT SKYBLUE (-5925 4100);
FORCEPROP 1 LAST MATERIAL CHIP
J 0
(-6375 4000);
DISPLAY 0.489362 (-6375 4000);
PAINT SKYBLUE (-6375 4000);
FORCEPROP 1 LAST VALUE 0
J 2
(-6175 4100);
DISPLAY 0.489362 (-6175 4100);
PAINT SKYBLUE (-6175 4100);
FORCEPROP 1 LAST PACK_TYPE 0402LF
J 0
(-5950 4000);
DISPLAY 0.489362 (-5950 4000);
PAINT SKYBLUE (-5950 4000);
FORCEPROP 1 LAST WATTAGE 1/16W
J 0
(-5950 4025);
DISPLAY 0.489362 (-5950 4025);
PAINT SKYBLUE (-5950 4025);
FORCEPROP 2 LAST CDS_LIB pure_quanta
J 0
(-6050 4075);
DISPLAY INVISIBLE (-6050 4075);
FORCEPROP 1 LAST PATH I27
J 0
(-6100 4225);
DISPLAY 0.978723 (-6100 4225);
PAINT WHITE (-6100 4225);
DISPLAY INVISIBLE (-6100 4225);
FORCEPROP 1 LAST PART_NUMBER CS00002JB13
J 0
(-6375 4025);
DISPLAY 0.489362 (-6375 4025);
PAINT SKYBLUE (-6375 4025);
DISPLAY INVISIBLE (-6375 4025);
FORCEADD Q_CAP..1
(-5750 3950);
FORCEPROP 1 LAST LOCATION PC639
J 0
(-5700 4000);
DISPLAY 0.489362 (-5700 4000);
PAINT SKYBLUE (-5700 4000);
FORCEPROP 0 LAST $SEC 1
J 0
(-5700 4025);
DISPLAY 0.680851 (-5700 4025);
PAINT MONO (-5700 4025);
DISPLAY INVISIBLE (-5700 4025);
FORCEPROP 0 LAST CDS_SEC 1
J 0
(-5700 4025);
DISPLAY 1.021277 (-5700 4025);
DISPLAY INVISIBLE (-5700 4025);
FORCEPROP 1 LASTPIN (-5750 4050) $PN 1
J 0
(-5740 4030);
DISPLAY 0.489362 (-5740 4030);
PAINT MONO (-5740 4030);
FORCEPROP 1 LASTPIN (-5750 3850) $PN 2
J 0
(-5740 3830);
DISPLAY 0.489362 (-5740 3830);
PAINT MONO (-5740 3830);
FORCEPROP 1 LAST PACK_TYPE 0402
J 0
(-5700 3850);
DISPLAY 0.489362 (-5700 3850);
PAINT SKYBLUE (-5700 3850);
FORCEPROP 1 LAST MATERIAL X7R
J 0
(-5700 3900);
DISPLAY 0.489362 (-5700 3900);
PAINT SKYBLUE (-5700 3900);
FORCEPROP 1 LAST VALUE 3300PF
J 0
(-5700 3975);
DISPLAY 0.489362 (-5700 3975);
PAINT SKYBLUE (-5700 3975);
FORCEPROP 1 LAST VOLTAGE 50V
J 0
(-5700 3950);
DISPLAY 0.489362 (-5700 3950);
PAINT SKYBLUE (-5700 3950);
FORCEPROP 1 LAST TOLERANCE 10%
J 0
(-5700 3925);
DISPLAY 0.489362 (-5700 3925);
PAINT SKYBLUE (-5700 3925);
FORCEPROP 2 LAST CDS_LIB pure_quanta
J 0
(-5750 3950);
DISPLAY INVISIBLE (-5750 3950);
FORCEPROP 1 LAST PATH I28
J 0
(-5700 4100);
DISPLAY 0.978723 (-5700 4100);
PAINT WHITE (-5700 4100);
DISPLAY INVISIBLE (-5700 4100);
FORCEPROP 1 LAST PART_NUMBER TMP_QCH2336K1B12
J 0
(-5700 3875);
DISPLAY 0.489362 (-5700 3875);
PAINT SKYBLUE (-5700 3875);
DISPLAY INVISIBLE (-5700 3875);
FORCEADD Q_RES..2
(-6750 4250);
FORCEPROP 1 LAST LOCATION PR229
J 0
(-6705 4375);
DISPLAY 0.489362 (-6705 4375);
PAINT SKYBLUE (-6705 4375);
FORCEPROP 0 LAST $SEC 1
J 0
(-6700 4425);
DISPLAY 0.680851 (-6700 4425);
PAINT MONO (-6700 4425);
DISPLAY INVISIBLE (-6700 4425);
FORCEPROP 0 LAST CDS_SEC 1
J 0
(-6700 4425);
DISPLAY 1.021277 (-6700 4425);
DISPLAY INVISIBLE (-6700 4425);
FORCEPROP 1 LASTPIN (-6750 4350) $PN 1
J 0
(-6745 4312);
DISPLAY 0.489362 (-6745 4312);
PAINT MONO (-6745 4312);
FORCEPROP 1 LASTPIN (-6750 4150) $PN 2
J 0
(-6745 4160);
DISPLAY 0.489362 (-6745 4160);
PAINT MONO (-6745 4160);
FORCEPROP 1 LAST VALUE 49.9
J 0
(-6700 4325);
DISPLAY 0.489362 (-6700 4325);
PAINT SKYBLUE (-6700 4325);
FORCEPROP 1 LAST PACK_TYPE 0402LF
J 0
(-6700 4075);
DISPLAY 0.489362 (-6700 4075);
PAINT SKYBLUE (-6700 4075);
FORCEPROP 1 LAST TOLERANCE 1%
J 0
(-6700 4275);
DISPLAY 0.489362 (-6700 4275);
PAINT SKYBLUE (-6700 4275);
FORCEPROP 1 LAST WATTAGE 1/16W
J 0
(-6700 4225);
DISPLAY 0.489362 (-6700 4225);
PAINT SKYBLUE (-6700 4225);
FORCEPROP 1 LAST MATERIAL CHIP
J 0
(-6700 4175);
DISPLAY 0.489362 (-6700 4175);
PAINT SKYBLUE (-6700 4175);
FORCEPROP 2 LAST CDS_LIB pure_quanta
J 0
(-6750 4250);
DISPLAY INVISIBLE (-6750 4250);
FORCEPROP 1 LAST PATH I29
J 0
(-6700 4425);
DISPLAY 0.978723 (-6700 4425);
PAINT WHITE (-6700 4425);
DISPLAY INVISIBLE (-6700 4425);
FORCEPROP 1 LAST PART_NUMBER CS04992FB07
J 0
(-6700 4125);
DISPLAY 0.489362 (-6700 4125);
PAINT SKYBLUE (-6700 4125);
DISPLAY INVISIBLE (-6700 4125);
FORCEADD UNIVERSAL_GND..1
(-6950 425);
FORCEPROP 3 LASTPIN (-6950 475) SIG_NAME GND\g
J 0
(-6940 485);
DISPLAY 0.659574 (-6940 485);
PAINT MONO (-6940 485);
DISPLAY INVISIBLE (-6940 485);
FORCEPROP 2 LAST CDS_LIB pure_quanta_power
J 0
(-6950 425);
DISPLAY INVISIBLE (-6950 425);
FORCEPROP 1 LAST HDL_POWER GND
J 1
(-6925 350);
DISPLAY 0.872340 (-6925 350);
PAINT GREEN (-6925 350);
DISPLAY INVISIBLE (-6925 350);
FORCEPROP 1 LAST PATH I3
J 0
(-6875 425);
DISPLAY 0.872340 (-6875 425);
PAINT AQUA (-6875 425);
DISPLAY INVISIBLE (-6875 425);
FORCEADD VCC_CORE..1
(-6750 4450);
FORCEPROP 3 LASTPIN (-6750 4400) SIG_NAME PVDD11_S3_P1\g
J 0
(-6740 4410);
DISPLAY 0.659574 (-6740 4410);
PAINT MONO (-6740 4410);
DISPLAY INVISIBLE (-6740 4410);
FORCEPROP 1 LAST HDL_POWER PVDD11_S3_P1
J 1
(-6750 4500);
DISPLAY 0.489362 (-6750 4500);
PAINT GREEN (-6750 4500);
FORCEPROP 2 LAST CDS_LIB pure_quanta_power
J 0
(-6750 4450);
DISPLAY INVISIBLE (-6750 4450);
FORCEPROP 1 LAST PATH I30
J 0
(-6700 4475);
DISPLAY 0.872340 (-6700 4475);
PAINT AQUA (-6700 4475);
DISPLAY INVISIBLE (-6700 4475);
FORCEADD OFFPAGE..2
R 2
(-6825 4675);
FORCEPROP 2 LAST $XR1 82 
J 0
(-7169 4675);
DISPLAY 0.638298 (-7169 4675);
PAINT MONO (-7169 4675);
FORCEPROP 2 LAST $XR0 83 
J 0
(-7079 4675);
DISPLAY 0.638298 (-7079 4675);
PAINT MONO (-7079 4675);
FORCEPROP 2 LAST CDS_LIB standard
J 0
(-6825 4675);
DISPLAY INVISIBLE (-6825 4675);
FORCEPROP 1 LAST OFFPAGE TRUE
J 2
(-7150 4550);
DISPLAY 0.872340 (-7150 4550);
PAINT GREEN (-7150 4550);
DISPLAY INVISIBLE (-7150 4550);
FORCEPROP 1 LAST COMMENT_BODY TRUE
J 2
(-6780 4580);
DISPLAY 0.872340 (-6780 4580);
PAINT GREEN (-6780 4580);
DISPLAY INVISIBLE (-6780 4580);
FORCEPROP 2 LAST PATH I31
J 0
(-7025 4725);
DISPLAY 0.680851 (-7025 4725);
DISPLAY INVISIBLE (-7025 4725);
FORCEADD OFFPAGE..2
R 2
(-6825 4825);
FORCEPROP 2 LAST $XR0 151 
J 0
(-7110 4825);
DISPLAY 0.638298 (-7110 4825);
PAINT MONO (-7110 4825);
FORCEPROP 2 LAST CDS_LIB standard
J 0
(-6825 4825);
DISPLAY INVISIBLE (-6825 4825);
FORCEPROP 1 LAST OFFPAGE TRUE
J 2
(-7150 4700);
DISPLAY 0.872340 (-7150 4700);
PAINT GREEN (-7150 4700);
DISPLAY INVISIBLE (-7150 4700);
FORCEPROP 1 LAST COMMENT_BODY TRUE
J 2
(-6780 4730);
DISPLAY 0.872340 (-6780 4730);
PAINT GREEN (-6780 4730);
DISPLAY INVISIBLE (-6780 4730);
FORCEPROP 2 LAST PATH I32
J 0
(-7075 4875);
DISPLAY 0.680851 (-7075 4875);
DISPLAY INVISIBLE (-7075 4875);
FORCEADD OFFPAGE..2
R 2
(-6825 4975);
FORCEPROP 2 LAST $XR0 151 
J 0
(-7110 4975);
DISPLAY 0.638298 (-7110 4975);
PAINT MONO (-7110 4975);
FORCEPROP 2 LAST CDS_LIB standard
J 0
(-6825 4975);
DISPLAY INVISIBLE (-6825 4975);
FORCEPROP 1 LAST OFFPAGE TRUE
J 2
(-7150 4850);
DISPLAY 0.872340 (-7150 4850);
PAINT GREEN (-7150 4850);
DISPLAY INVISIBLE (-7150 4850);
FORCEPROP 1 LAST COMMENT_BODY TRUE
J 2
(-6780 4880);
DISPLAY 0.872340 (-6780 4880);
PAINT GREEN (-6780 4880);
DISPLAY INVISIBLE (-6780 4880);
FORCEPROP 2 LAST PATH I33
J 0
(-7075 5025);
DISPLAY 0.680851 (-7075 5025);
DISPLAY INVISIBLE (-7075 5025);
FORCEADD OFFPAGE..2
R 2
(-6800 6125);
FORCEPROP 2 LAST $XR0 81 
J 0
(-7024 6125);
DISPLAY 0.638298 (-7024 6125);
PAINT MONO (-7024 6125);
FORCEPROP 2 LAST CDS_LIB standard
J 0
(-6800 6125);
DISPLAY INVISIBLE (-6800 6125);
FORCEPROP 1 LAST OFFPAGE TRUE
J 2
(-7125 6000);
DISPLAY 0.872340 (-7125 6000);
PAINT GREEN (-7125 6000);
DISPLAY INVISIBLE (-7125 6000);
FORCEPROP 1 LAST COMMENT_BODY TRUE
J 2
(-6755 6030);
DISPLAY 0.872340 (-6755 6030);
PAINT GREEN (-6755 6030);
DISPLAY INVISIBLE (-6755 6030);
FORCEPROP 2 LAST PATH I34
J 0
(-7050 6175);
DISPLAY 0.680851 (-7050 6175);
DISPLAY INVISIBLE (-7050 6175);
FORCEADD OFFPAGE..4
R 4
(-6800 5975);
FORCEPROP 2 LAST $XR0 81 
J 0
(-7051 5975);
DISPLAY 0.638298 (-7051 5975);
PAINT MONO (-7051 5975);
FORCEPROP 2 LAST CDS_LIB standard
R 2
J 2
(-6800 5975);
DISPLAY INVISIBLE (-6800 5975);
FORCEPROP 1 LAST OFFPAGE TRUE
R 2
J 0
(-7125 6100);
DISPLAY 0.872340 (-7125 6100);
PAINT GREEN (-7125 6100);
DISPLAY INVISIBLE (-7125 6100);
FORCEPROP 1 LAST COMMENT_BODY TRUE
R 2
J 0
(-6775 6075);
DISPLAY 0.872340 (-6775 6075);
PAINT GREEN (-6775 6075);
DISPLAY INVISIBLE (-6775 6075);
FORCEPROP 2 LAST PATH I35
J 0
(-7000 6025);
DISPLAY 0.680851 (-7000 6025);
DISPLAY INVISIBLE (-7000 6025);
FORCEADD VCC_CORE..1
(-6600 6525);
FORCEPROP 3 LASTPIN (-6600 6475) SIG_NAME P3V3_AUX\g
J 0
(-6590 6485);
DISPLAY 0.659574 (-6590 6485);
PAINT MONO (-6590 6485);
DISPLAY INVISIBLE (-6590 6485);
FORCEPROP 1 LAST HDL_POWER P3V3_AUX
J 1
(-6600 6575);
DISPLAY 0.489362 (-6600 6575);
PAINT GREEN (-6600 6575);
FORCEPROP 2 LAST CDS_LIB pure_quanta_power
J 0
(-6600 6525);
DISPLAY INVISIBLE (-6600 6525);
FORCEPROP 1 LAST PATH I36
J 0
(-6550 6550);
DISPLAY 0.872340 (-6550 6550);
PAINT AQUA (-6550 6550);
DISPLAY INVISIBLE (-6550 6550);
FORCEADD Q_RES..1
(-6200 6400);
FORCEPROP 1 LAST LOCATION R8380
J 0
(-6250 6450);
DISPLAY 0.489362 (-6250 6450);
PAINT SKYBLUE (-6250 6450);
FORCEPROP 0 LAST $SEC 1
J 0
(-6250 6500);
DISPLAY 0.680851 (-6250 6500);
PAINT MONO (-6250 6500);
DISPLAY INVISIBLE (-6250 6500);
FORCEPROP 0 LAST CDS_SEC 1
J 0
(-6250 6500);
DISPLAY 1.021277 (-6250 6500);
DISPLAY INVISIBLE (-6250 6500);
FORCEPROP 1 LASTPIN (-6300 6400) $PN 1
J 0
(-6288 6412);
DISPLAY 0.489362 (-6288 6412);
PAINT MONO (-6288 6412);
FORCEPROP 1 LASTPIN (-6100 6400) $PN 2
J 0
(-6138 6412);
DISPLAY 0.489362 (-6138 6412);
PAINT MONO (-6138 6412);
FORCEPROP 1 LAST PACK_TYPE 0402LF
J 0
(-6100 6300);
DISPLAY 0.489362 (-6100 6300);
PAINT SKYBLUE (-6100 6300);
FORCEPROP 1 LAST VALUE 1K
J 2
(-6350 6425);
DISPLAY 0.489362 (-6350 6425);
PAINT SKYBLUE (-6350 6425);
FORCEPROP 1 LAST MATERIAL CHIP
J 0
(-6525 6300);
DISPLAY 0.489362 (-6525 6300);
PAINT SKYBLUE (-6525 6300);
FORCEPROP 1 LAST WATTAGE 1/16W
J 0
(-6100 6350);
DISPLAY 0.489362 (-6100 6350);
PAINT SKYBLUE (-6100 6350);
FORCEPROP 1 LAST TOLERANCE 1%
J 0
(-6075 6425);
DISPLAY 0.489362 (-6075 6425);
PAINT SKYBLUE (-6075 6425);
FORCEPROP 2 LAST CDS_LIB pure_quanta
J 0
(-6200 6400);
DISPLAY INVISIBLE (-6200 6400);
FORCEPROP 1 LAST PATH I37
J 0
(-6250 6550);
DISPLAY 0.978723 (-6250 6550);
PAINT WHITE (-6250 6550);
DISPLAY INVISIBLE (-6250 6550);
FORCEPROP 1 LAST PART_NUMBER CS21002FB06
J 0
(-6525 6350);
DISPLAY 0.489362 (-6525 6350);
PAINT SKYBLUE (-6525 6350);
DISPLAY INVISIBLE (-6525 6350);
FORCEADD Q_RES..1
(-6050 4675);
FORCEPROP 1 LAST LOCATION R8383
J 0
(-6100 4725);
DISPLAY 0.489362 (-6100 4725);
PAINT SKYBLUE (-6100 4725);
FORCEPROP 0 LAST $SEC 1
J 0
(-6100 4750);
DISPLAY 0.680851 (-6100 4750);
PAINT MONO (-6100 4750);
DISPLAY INVISIBLE (-6100 4750);
FORCEPROP 0 LAST CDS_SEC 1
J 0
(-6100 4750);
DISPLAY 1.021277 (-6100 4750);
DISPLAY INVISIBLE (-6100 4750);
FORCEPROP 1 LASTPIN (-6150 4675) $PN 1
J 0
(-6138 4687);
DISPLAY 0.489362 (-6138 4687);
PAINT MONO (-6138 4687);
FORCEPROP 1 LASTPIN (-5950 4675) $PN 2
J 0
(-5988 4687);
DISPLAY 0.489362 (-5988 4687);
PAINT MONO (-5988 4687);
FORCEPROP 1 LAST TOLERANCE 5%
J 0
(-5925 4700);
DISPLAY 0.489362 (-5925 4700);
PAINT SKYBLUE (-5925 4700);
FORCEPROP 1 LAST WATTAGE 1/16W
J 0
(-5950 4625);
DISPLAY 0.489362 (-5950 4625);
PAINT SKYBLUE (-5950 4625);
FORCEPROP 1 LAST MATERIAL CHIP
J 0
(-6300 4600);
DISPLAY 0.489362 (-6300 4600);
PAINT SKYBLUE (-6300 4600);
FORCEPROP 1 LAST VALUE 33
J 2
(-6175 4700);
DISPLAY 0.489362 (-6175 4700);
PAINT SKYBLUE (-6175 4700);
FORCEPROP 1 LAST PACK_TYPE 0402LF
J 0
(-5950 4600);
DISPLAY 0.489362 (-5950 4600);
PAINT SKYBLUE (-5950 4600);
FORCEPROP 2 LAST CDS_LIB pure_quanta
J 0
(-6050 4675);
DISPLAY INVISIBLE (-6050 4675);
FORCEPROP 1 LAST PATH I38
J 0
(-6100 4825);
DISPLAY 0.978723 (-6100 4825);
PAINT WHITE (-6100 4825);
DISPLAY INVISIBLE (-6100 4825);
FORCEPROP 1 LAST PART_NUMBER CS03302JB10
J 0
(-6300 4625);
DISPLAY 0.489362 (-6300 4625);
PAINT SKYBLUE (-6300 4625);
DISPLAY INVISIBLE (-6300 4625);
FORCEADD Q_RES..1
(-6050 4825);
FORCEPROP 1 LAST LOCATION R8382
J 0
(-6100 4875);
DISPLAY 0.489362 (-6100 4875);
PAINT SKYBLUE (-6100 4875);
FORCEPROP 0 LAST $SEC 1
J 0
(-6100 4900);
DISPLAY 0.680851 (-6100 4900);
PAINT MONO (-6100 4900);
DISPLAY INVISIBLE (-6100 4900);
FORCEPROP 0 LAST CDS_SEC 1
J 0
(-6100 4900);
DISPLAY 1.021277 (-6100 4900);
DISPLAY INVISIBLE (-6100 4900);
FORCEPROP 1 LASTPIN (-6150 4825) $PN 1
J 0
(-6138 4837);
DISPLAY 0.489362 (-6138 4837);
PAINT MONO (-6138 4837);
FORCEPROP 1 LASTPIN (-5950 4825) $PN 2
J 0
(-5988 4837);
DISPLAY 0.489362 (-5988 4837);
PAINT MONO (-5988 4837);
FORCEPROP 1 LAST VALUE 0
J 2
(-6175 4850);
DISPLAY 0.489362 (-6175 4850);
PAINT SKYBLUE (-6175 4850);
FORCEPROP 1 LAST WATTAGE 1/16W
J 0
(-5950 4775);
DISPLAY 0.489362 (-5950 4775);
PAINT SKYBLUE (-5950 4775);
FORCEPROP 1 LAST TOLERANCE 5%
J 0
(-5925 4850);
DISPLAY 0.489362 (-5925 4850);
PAINT SKYBLUE (-5925 4850);
FORCEPROP 1 LAST PACK_TYPE 0402LF
J 0
(-5950 4750);
DISPLAY 0.489362 (-5950 4750);
PAINT SKYBLUE (-5950 4750);
FORCEPROP 1 LAST MATERIAL CHIP
J 0
(-6300 4750);
DISPLAY 0.489362 (-6300 4750);
PAINT SKYBLUE (-6300 4750);
FORCEPROP 2 LAST CDS_LIB pure_quanta
J 0
(-6050 4825);
DISPLAY INVISIBLE (-6050 4825);
FORCEPROP 1 LAST PATH I39
J 0
(-6100 4975);
DISPLAY 0.978723 (-6100 4975);
PAINT WHITE (-6100 4975);
DISPLAY INVISIBLE (-6100 4975);
FORCEPROP 1 LAST PART_NUMBER CS00002JB13
J 0
(-6300 4775);
DISPLAY 0.489362 (-6300 4775);
PAINT SKYBLUE (-6300 4775);
DISPLAY INVISIBLE (-6300 4775);
FORCEADD Q_CAP..1
(-6950 675);
FORCEPROP 1 LAST LOCATION PC638
J 0
(-6875 775);
DISPLAY 0.489362 (-6875 775);
PAINT SKYBLUE (-6875 775);
FORCEPROP 0 LAST $SEC 1
J 0
(-6900 800);
DISPLAY 0.680851 (-6900 800);
PAINT MONO (-6900 800);
DISPLAY INVISIBLE (-6900 800);
FORCEPROP 0 LAST CDS_SEC 1
J 0
(-6900 800);
DISPLAY 1.021277 (-6900 800);
DISPLAY INVISIBLE (-6900 800);
FORCEPROP 1 LASTPIN (-6950 775) $PN 1
J 0
(-6940 755);
DISPLAY 0.489362 (-6940 755);
PAINT MONO (-6940 755);
FORCEPROP 1 LASTPIN (-6950 575) $PN 2
J 0
(-6940 555);
DISPLAY 0.489362 (-6940 555);
PAINT MONO (-6940 555);
FORCEPROP 1 LAST TOLERANCE 10%
J 0
(-6875 625);
DISPLAY 0.489362 (-6875 625);
PAINT SKYBLUE (-6875 625);
FORCEPROP 1 LAST PACK_TYPE 0402
J 0
(-6875 475);
DISPLAY 0.489362 (-6875 475);
PAINT SKYBLUE (-6875 475);
FORCEPROP 1 LAST VOLTAGE 25V
J 0
(-6875 675);
DISPLAY 0.489362 (-6875 675);
PAINT SKYBLUE (-6875 675);
FORCEPROP 1 LAST MATERIAL X7R
J 0
(-6875 575);
DISPLAY 0.489362 (-6875 575);
PAINT SKYBLUE (-6875 575);
FORCEPROP 1 LAST VALUE 0.1UF
J 0
(-6875 725);
DISPLAY 0.489362 (-6875 725);
PAINT SKYBLUE (-6875 725);
FORCEPROP 2 LAST CDS_LIB pure_quanta
J 0
(-6950 675);
DISPLAY INVISIBLE (-6950 675);
FORCEPROP 1 LAST PATH I4
J 0
(-6900 825);
DISPLAY 0.978723 (-6900 825);
PAINT WHITE (-6900 825);
DISPLAY INVISIBLE (-6900 825);
FORCEPROP 1 LAST PART_NUMBER CH4104K1B00
J 0
(-6875 525);
DISPLAY 0.489362 (-6875 525);
PAINT SKYBLUE (-6875 525);
DISPLAY INVISIBLE (-6875 525);
FORCEADD Q_RES..1
(-6050 4975);
FORCEPROP 1 LAST LOCATION R8381
J 0
(-6100 5025);
DISPLAY 0.489362 (-6100 5025);
PAINT SKYBLUE (-6100 5025);
FORCEPROP 0 LAST $SEC 1
J 0
(-6100 5050);
DISPLAY 0.680851 (-6100 5050);
PAINT MONO (-6100 5050);
DISPLAY INVISIBLE (-6100 5050);
FORCEPROP 0 LAST CDS_SEC 1
J 0
(-6100 5050);
DISPLAY 1.021277 (-6100 5050);
DISPLAY INVISIBLE (-6100 5050);
FORCEPROP 1 LASTPIN (-6150 4975) $PN 1
J 0
(-6138 4987);
DISPLAY 0.489362 (-6138 4987);
PAINT MONO (-6138 4987);
FORCEPROP 1 LASTPIN (-5950 4975) $PN 2
J 0
(-5988 4987);
DISPLAY 0.489362 (-5988 4987);
PAINT MONO (-5988 4987);
FORCEPROP 1 LAST MATERIAL CHIP
J 0
(-6300 4900);
DISPLAY 0.489362 (-6300 4900);
PAINT SKYBLUE (-6300 4900);
FORCEPROP 1 LAST TOLERANCE 5%
J 0
(-5925 5000);
DISPLAY 0.489362 (-5925 5000);
PAINT SKYBLUE (-5925 5000);
FORCEPROP 1 LAST VALUE 0
J 2
(-6175 5000);
DISPLAY 0.489362 (-6175 5000);
PAINT SKYBLUE (-6175 5000);
FORCEPROP 1 LAST WATTAGE 1/16W
J 0
(-5950 4925);
DISPLAY 0.489362 (-5950 4925);
PAINT SKYBLUE (-5950 4925);
FORCEPROP 1 LAST PACK_TYPE 0402LF
J 0
(-5950 4900);
DISPLAY 0.489362 (-5950 4900);
PAINT SKYBLUE (-5950 4900);
FORCEPROP 2 LAST CDS_LIB pure_quanta
J 0
(-6050 4975);
DISPLAY INVISIBLE (-6050 4975);
FORCEPROP 1 LAST PATH I40
J 0
(-6100 5125);
DISPLAY 0.978723 (-6100 5125);
PAINT WHITE (-6100 5125);
DISPLAY INVISIBLE (-6100 5125);
FORCEPROP 1 LAST PART_NUMBER CS00002JB13
J 0
(-6300 4925);
DISPLAY 0.489362 (-6300 4925);
PAINT SKYBLUE (-6300 4925);
DISPLAY INVISIBLE (-6300 4925);
FORCEADD UNIVERSAL_GND..1
(-6050 5125);
FORCEPROP 3 LASTPIN (-6050 5175) SIG_NAME GND\g
J 0
(-6040 5185);
DISPLAY 0.659574 (-6040 5185);
PAINT MONO (-6040 5185);
DISPLAY INVISIBLE (-6040 5185);
FORCEPROP 2 LAST CDS_LIB pure_quanta_power
J 0
(-6050 5125);
DISPLAY INVISIBLE (-6050 5125);
FORCEPROP 1 LAST HDL_POWER GND
J 1
(-6025 5050);
DISPLAY 0.872340 (-6025 5050);
PAINT GREEN (-6025 5050);
DISPLAY INVISIBLE (-6025 5050);
FORCEPROP 1 LAST PATH I41
J 0
(-5975 5125);
DISPLAY 0.872340 (-5975 5125);
PAINT AQUA (-5975 5125);
DISPLAY INVISIBLE (-5975 5125);
FORCEADD Q_RES..1
(-5975 5975);
FORCEPROP 1 LAST LOCATION R8386
J 0
(-6025 6000);
DISPLAY 0.489362 (-6025 6000);
PAINT SKYBLUE (-6025 6000);
FORCEPROP 0 LAST $SEC 1
J 0
(-5850 6025);
DISPLAY 0.680851 (-5850 6025);
PAINT MONO (-5850 6025);
DISPLAY INVISIBLE (-5850 6025);
FORCEPROP 0 LAST CDS_SEC 1
J 0
(-5850 6025);
DISPLAY 1.021277 (-5850 6025);
DISPLAY INVISIBLE (-5850 6025);
FORCEPROP 1 LASTPIN (-6075 5975) $PN 1
J 0
(-6063 5987);
DISPLAY 0.489362 (-6063 5987);
PAINT MONO (-6063 5987);
FORCEPROP 1 LASTPIN (-5875 5975) $PN 2
J 0
(-5913 5987);
DISPLAY 0.489362 (-5913 5987);
PAINT MONO (-5913 5987);
FORCEPROP 1 LAST PACK_TYPE 0402LF
J 0
(-5875 5900);
DISPLAY 0.489362 (-5875 5900);
PAINT SKYBLUE (-5875 5900);
FORCEPROP 1 LAST TOLERANCE 5%
J 0
(-5850 6000);
DISPLAY 0.489362 (-5850 6000);
PAINT SKYBLUE (-5850 6000);
FORCEPROP 1 LAST VALUE 0
J 2
(-6100 6000);
DISPLAY 0.489362 (-6100 6000);
PAINT SKYBLUE (-6100 6000);
FORCEPROP 1 LAST MATERIAL CHIP
J 0
(-6225 5900);
DISPLAY 0.489362 (-6225 5900);
PAINT SKYBLUE (-6225 5900);
FORCEPROP 1 LAST WATTAGE 1/16W
J 0
(-5875 5925);
DISPLAY 0.489362 (-5875 5925);
PAINT SKYBLUE (-5875 5925);
FORCEPROP 2 LAST CDS_LIB pure_quanta
J 0
(-5975 5975);
DISPLAY INVISIBLE (-5975 5975);
FORCEPROP 1 LAST PATH I42
J 0
(-6025 6125);
DISPLAY 0.978723 (-6025 6125);
PAINT WHITE (-6025 6125);
DISPLAY INVISIBLE (-6025 6125);
FORCEPROP 1 LAST PART_NUMBER CS00002JB13
J 0
(-6225 5925);
DISPLAY 0.489362 (-6225 5925);
PAINT SKYBLUE (-6225 5925);
DISPLAY INVISIBLE (-6225 5925);
FORCEADD Q_RES..1
(-5975 6125);
FORCEPROP 1 LAST LOCATION R8385
J 0
(-6025 6175);
DISPLAY 0.489362 (-6025 6175);
PAINT SKYBLUE (-6025 6175);
FORCEPROP 0 LAST $SEC 1
J 0
(-6025 6225);
DISPLAY 0.680851 (-6025 6225);
PAINT MONO (-6025 6225);
DISPLAY INVISIBLE (-6025 6225);
FORCEPROP 0 LAST CDS_SEC 1
J 0
(-6025 6225);
DISPLAY 1.021277 (-6025 6225);
DISPLAY INVISIBLE (-6025 6225);
FORCEPROP 1 LASTPIN (-6075 6125) $PN 1
J 0
(-6063 6137);
DISPLAY 0.489362 (-6063 6137);
PAINT MONO (-6063 6137);
FORCEPROP 1 LASTPIN (-5875 6125) $PN 2
J 0
(-5913 6137);
DISPLAY 0.489362 (-5913 6137);
PAINT MONO (-5913 6137);
FORCEPROP 1 LAST PACK_TYPE 0402LF
J 0
(-5875 6050);
DISPLAY 0.489362 (-5875 6050);
PAINT SKYBLUE (-5875 6050);
FORCEPROP 1 LAST MATERIAL CHIP
J 0
(-6225 6050);
DISPLAY 0.489362 (-6225 6050);
PAINT SKYBLUE (-6225 6050);
FORCEPROP 1 LAST TOLERANCE 5%
J 0
(-5850 6150);
DISPLAY 0.489362 (-5850 6150);
PAINT SKYBLUE (-5850 6150);
FORCEPROP 1 LAST WATTAGE 1/16W
J 0
(-5875 6075);
DISPLAY 0.489362 (-5875 6075);
PAINT SKYBLUE (-5875 6075);
FORCEPROP 1 LAST VALUE 0
J 2
(-6100 6150);
DISPLAY 0.489362 (-6100 6150);
PAINT SKYBLUE (-6100 6150);
FORCEPROP 2 LAST CDS_LIB pure_quanta
J 0
(-5975 6125);
DISPLAY INVISIBLE (-5975 6125);
FORCEPROP 1 LAST PATH I43
J 0
(-6025 6275);
DISPLAY 0.978723 (-6025 6275);
PAINT WHITE (-6025 6275);
DISPLAY INVISIBLE (-6025 6275);
FORCEPROP 1 LAST PART_NUMBER CS00002JB13
J 0
(-6225 6075);
DISPLAY 0.489362 (-6225 6075);
PAINT SKYBLUE (-6225 6075);
DISPLAY INVISIBLE (-6225 6075);
FORCEADD Q_CAP..2
(-5300 5850);
FORCEPROP 1 LAST LOCATION C642
J 1
(-5300 5900);
DISPLAY 0.489362 (-5300 5900);
PAINT SKYBLUE (-5300 5900);
FORCEPROP 0 LAST $SEC 1
J 0
(-5300 5950);
DISPLAY 0.680851 (-5300 5950);
PAINT MONO (-5300 5950);
DISPLAY INVISIBLE (-5300 5950);
FORCEPROP 0 LAST CDS_SEC 1
J 0
(-5300 5950);
DISPLAY 1.021277 (-5300 5950);
DISPLAY INVISIBLE (-5300 5950);
FORCEPROP 1 LASTPIN (-5400 5850) $PN 1
J 0
(-5410 5865);
DISPLAY 0.489362 (-5410 5865);
PAINT MONO (-5410 5865);
FORCEPROP 1 LASTPIN (-5200 5850) $PN 2
J 0
(-5215 5865);
DISPLAY 0.489362 (-5215 5865);
PAINT MONO (-5215 5865);
FORCEPROP 1 LAST VALUE 1000PF
J 2
(-5475 5875);
DISPLAY 0.489362 (-5475 5875);
PAINT SKYBLUE (-5475 5875);
FORCEPROP 1 LAST VOLTAGE 50V
J 0
(-5150 5875);
DISPLAY 0.489362 (-5150 5875);
PAINT SKYBLUE (-5150 5875);
FORCEPROP 1 LAST MATERIAL X7R
J 0
(-5725 5800);
DISPLAY 0.489362 (-5725 5800);
PAINT SKYBLUE (-5725 5800);
FORCEPROP 1 LAST TOLERANCE 5%
J 0
(-5200 5800);
DISPLAY 0.489362 (-5200 5800);
PAINT SKYBLUE (-5200 5800);
FORCEPROP 1 LAST PACK_TYPE 0402
J 0
(-5200 5825);
DISPLAY 0.489362 (-5200 5825);
PAINT SKYBLUE (-5200 5825);
FORCEPROP 2 LAST CDS_LIB pure_quanta
J 0
(-5300 5850);
DISPLAY INVISIBLE (-5300 5850);
FORCEPROP 1 LAST PATH I44
J 0
(-5300 6050);
DISPLAY 0.978723 (-5300 6050);
PAINT WHITE (-5300 6050);
DISPLAY INVISIBLE (-5300 6050);
FORCEPROP 1 LAST PART_NUMBER TMP_QCH21006JB10
J 0
(-5725 5825);
DISPLAY 0.489362 (-5725 5825);
PAINT SKYBLUE (-5725 5825);
DISPLAY INVISIBLE (-5725 5825);
FORCEADD UNIVERSAL_GND..1
(-5075 5775);
FORCEPROP 3 LASTPIN (-5075 5825) SIG_NAME GND\g
J 0
(-5065 5835);
DISPLAY 0.659574 (-5065 5835);
PAINT MONO (-5065 5835);
DISPLAY INVISIBLE (-5065 5835);
FORCEPROP 2 LAST CDS_LIB pure_quanta_power
J 0
(-5075 5775);
DISPLAY INVISIBLE (-5075 5775);
FORCEPROP 1 LAST HDL_POWER GND
J 1
(-5050 5700);
DISPLAY 0.872340 (-5050 5700);
PAINT GREEN (-5050 5700);
DISPLAY INVISIBLE (-5050 5700);
FORCEPROP 1 LAST PATH I45
J 0
(-5000 5775);
DISPLAY 0.872340 (-5000 5775);
PAINT AQUA (-5000 5775);
DISPLAY INVISIBLE (-5000 5775);
FORCEADD Q_CAP..2
(-5325 6400);
FORCEPROP 1 LAST LOCATION C8641
J 1
(-5325 6475);
DISPLAY 0.489362 (-5325 6475);
PAINT SKYBLUE (-5325 6475);
FORCEPROP 0 LAST $SEC 1
J 0
(-5325 6550);
DISPLAY 0.680851 (-5325 6550);
PAINT MONO (-5325 6550);
DISPLAY INVISIBLE (-5325 6550);
FORCEPROP 0 LAST CDS_SEC 1
J 0
(-5325 6550);
DISPLAY 1.021277 (-5325 6550);
DISPLAY INVISIBLE (-5325 6550);
FORCEPROP 1 LASTPIN (-5425 6400) $PN 1
J 0
(-5435 6415);
DISPLAY 0.489362 (-5435 6415);
PAINT MONO (-5435 6415);
FORCEPROP 1 LASTPIN (-5225 6400) $PN 2
J 0
(-5240 6415);
DISPLAY 0.489362 (-5240 6415);
PAINT MONO (-5240 6415);
FORCEPROP 1 LAST MATERIAL EMPTY
J 0
(-5600 6275);
DISPLAY 0.489362 (-5600 6275);
PAINT RED (-5600 6275);
FORCEPROP 1 LAST VOLTAGE 50V
J 0
(-5225 6450);
DISPLAY 0.489362 (-5225 6450);
PAINT SKYBLUE (-5225 6450);
FORCEPROP 1 LAST PACK_TYPE 0402
J 0
(-5200 6325);
DISPLAY 0.489362 (-5200 6325);
PAINT SKYBLUE (-5200 6325);
FORCEPROP 1 LAST VALUE 1000PF
J 2
(-5450 6450);
DISPLAY 0.489362 (-5450 6450);
PAINT SKYBLUE (-5450 6450);
FORCEPROP 1 LAST TOLERANCE 5%
J 0
(-5200 6275);
DISPLAY 0.489362 (-5200 6275);
PAINT SKYBLUE (-5200 6275);
FORCEPROP 2 LAST CDS_LIB pure_quanta
J 0
(-5325 6400);
DISPLAY INVISIBLE (-5325 6400);
FORCEPROP 1 LAST PATH I46
J 0
(-5325 6600);
DISPLAY 0.978723 (-5325 6600);
PAINT WHITE (-5325 6600);
DISPLAY INVISIBLE (-5325 6600);
FORCEPROP 1 LAST PART_NUMBER TMP_QCH21006JB10
J 1
(-5475 6325);
DISPLAY 0.489362 (-5475 6325);
PAINT SKYBLUE (-5475 6325);
DISPLAY INVISIBLE (-5475 6325);
FORCEADD UNIVERSAL_GND..1
(-5075 6325);
FORCEPROP 3 LASTPIN (-5075 6375) SIG_NAME GND\g
J 0
(-5065 6385);
DISPLAY 0.659574 (-5065 6385);
PAINT MONO (-5065 6385);
DISPLAY INVISIBLE (-5065 6385);
FORCEPROP 2 LAST CDS_LIB pure_quanta_power
J 0
(-5075 6325);
DISPLAY INVISIBLE (-5075 6325);
FORCEPROP 1 LAST HDL_POWER GND
J 1
(-5050 6250);
DISPLAY 0.872340 (-5050 6250);
PAINT GREEN (-5050 6250);
DISPLAY INVISIBLE (-5050 6250);
FORCEPROP 1 LAST PATH I47
J 0
(-5000 6325);
DISPLAY 0.872340 (-5000 6325);
PAINT AQUA (-5000 6325);
DISPLAY INVISIBLE (-5000 6325);
FORCEADD UNIVERSAL_GND..1
(-3450 450);
FORCEPROP 3 LASTPIN (-3450 500) SIG_NAME GND\g
J 0
(-3440 510);
DISPLAY 0.659574 (-3440 510);
PAINT MONO (-3440 510);
DISPLAY INVISIBLE (-3440 510);
FORCEPROP 2 LAST CDS_LIB pure_quanta_power
J 0
(-3450 450);
DISPLAY INVISIBLE (-3450 450);
FORCEPROP 1 LAST HDL_POWER GND
J 1
(-3425 375);
DISPLAY 0.872340 (-3425 375);
PAINT GREEN (-3425 375);
DISPLAY INVISIBLE (-3425 375);
FORCEPROP 1 LAST PATH I48
J 0
(-3375 450);
DISPLAY 0.872340 (-3375 450);
PAINT AQUA (-3375 450);
DISPLAY INVISIBLE (-3375 450);
FORCEADD Q_CAP..1
(-3450 725);
FORCEPROP 1 LAST LOCATION PC643
J 0
(-3400 825);
DISPLAY 0.489362 (-3400 825);
PAINT SKYBLUE (-3400 825);
FORCEPROP 0 LAST $SEC 1
J 0
(-3400 850);
DISPLAY 0.680851 (-3400 850);
PAINT MONO (-3400 850);
DISPLAY INVISIBLE (-3400 850);
FORCEPROP 0 LAST CDS_SEC 1
J 0
(-3400 850);
DISPLAY 1.021277 (-3400 850);
DISPLAY INVISIBLE (-3400 850);
FORCEPROP 1 LASTPIN (-3450 825) $PN 1
J 0
(-3440 805);
DISPLAY 0.489362 (-3440 805);
PAINT MONO (-3440 805);
FORCEPROP 1 LASTPIN (-3450 625) $PN 2
J 0
(-3440 605);
DISPLAY 0.489362 (-3440 605);
PAINT MONO (-3440 605);
FORCEPROP 1 LAST PACK_TYPE 0402
J 0
(-3400 525);
DISPLAY 0.489362 (-3400 525);
PAINT SKYBLUE (-3400 525);
FORCEPROP 1 LAST VOLTAGE 50V
J 0
(-3400 725);
DISPLAY 0.489362 (-3400 725);
PAINT SKYBLUE (-3400 725);
FORCEPROP 1 LAST VALUE 470PF
J 0
(-3400 775);
DISPLAY 0.489362 (-3400 775);
PAINT SKYBLUE (-3400 775);
FORCEPROP 1 LAST TOLERANCE 10%
J 0
(-3400 675);
DISPLAY 0.489362 (-3400 675);
PAINT SKYBLUE (-3400 675);
FORCEPROP 1 LAST MATERIAL X7R
J 0
(-3400 625);
DISPLAY 0.489362 (-3400 625);
PAINT SKYBLUE (-3400 625);
FORCEPROP 2 LAST CDS_LIB pure_quanta
J 0
(-3450 725);
DISPLAY INVISIBLE (-3450 725);
FORCEPROP 1 LAST PATH I49
J 0
(-3400 875);
DISPLAY 0.978723 (-3400 875);
PAINT WHITE (-3400 875);
DISPLAY INVISIBLE (-3400 875);
FORCEPROP 1 LAST PART_NUMBER TMP_QCH14706KB18
J 0
(-3400 575);
DISPLAY 0.489362 (-3400 575);
PAINT SKYBLUE (-3400 575);
DISPLAY INVISIBLE (-3400 575);
FORCEADD UNIVERSAL_GND..1
(-6525 400);
FORCEPROP 3 LASTPIN (-6525 450) SIG_NAME GND\g
J 0
(-6515 460);
DISPLAY 0.659574 (-6515 460);
PAINT MONO (-6515 460);
DISPLAY INVISIBLE (-6515 460);
FORCEPROP 2 LAST CDS_LIB pure_quanta_power
J 0
(-6525 400);
DISPLAY INVISIBLE (-6525 400);
FORCEPROP 1 LAST HDL_POWER GND
J 1
(-6500 325);
DISPLAY 0.872340 (-6500 325);
PAINT GREEN (-6500 325);
DISPLAY INVISIBLE (-6500 325);
FORCEPROP 1 LAST PATH I5
J 0
(-6450 400);
DISPLAY 0.872340 (-6450 400);
PAINT AQUA (-6450 400);
DISPLAY INVISIBLE (-6450 400);
FORCEADD OFFPAGE..4
(-3125 925);
FORCEPROP 2 LAST $XR0 225 
J 0
(-2939 925);
DISPLAY 0.638298 (-2939 925);
PAINT MONO (-2939 925);
FORCEPROP 2 LAST CDS_LIB standard
J 0
(-3125 925);
DISPLAY INVISIBLE (-3125 925);
FORCEPROP 1 LAST OFFPAGE TRUE
J 0
(-2800 800);
DISPLAY 0.872340 (-2800 800);
PAINT GREEN (-2800 800);
DISPLAY INVISIBLE (-2800 800);
FORCEPROP 1 LAST COMMENT_BODY TRUE
J 0
(-3150 825);
DISPLAY 0.872340 (-3150 825);
PAINT GREEN (-3150 825);
DISPLAY INVISIBLE (-3150 825);
FORCEPROP 2 LAST PATH I50
J 0
(-2925 975);
DISPLAY 0.680851 (-2925 975);
DISPLAY INVISIBLE (-2925 975);
FORCEADD Q_RES..1
(-3125 1225);
FORCEPROP 1 LAST LOCATION PR415
J 0
(-3175 1275);
DISPLAY 0.489362 (-3175 1275);
PAINT SKYBLUE (-3175 1275);
FORCEPROP 0 LAST $SEC 1
J 0
(-3175 1325);
DISPLAY 0.680851 (-3175 1325);
PAINT MONO (-3175 1325);
DISPLAY INVISIBLE (-3175 1325);
FORCEPROP 0 LAST CDS_SEC 1
J 0
(-3175 1325);
DISPLAY 1.021277 (-3175 1325);
DISPLAY INVISIBLE (-3175 1325);
FORCEPROP 1 LASTPIN (-3225 1225) $PN 1
J 0
(-3213 1237);
DISPLAY 0.489362 (-3213 1237);
PAINT MONO (-3213 1237);
FORCEPROP 1 LASTPIN (-3025 1225) $PN 2
J 0
(-3063 1237);
DISPLAY 0.489362 (-3063 1237);
PAINT MONO (-3063 1237);
FORCEPROP 1 LAST PACK_TYPE 0402LF
J 0
(-3025 1175);
DISPLAY 0.489362 (-3025 1175);
PAINT SKYBLUE (-3025 1175);
FORCEPROP 1 LAST MATERIAL CHIP
J 0
(-3450 1175);
DISPLAY 0.489362 (-3450 1175);
PAINT SKYBLUE (-3450 1175);
FORCEPROP 1 LAST WATTAGE 1/16W
J 2
(-3200 1175);
DISPLAY 0.489362 (-3200 1175);
PAINT SKYBLUE (-3200 1175);
FORCEPROP 1 LAST TOLERANCE 5%
J 0
(-3100 1175);
DISPLAY 0.489362 (-3100 1175);
PAINT SKYBLUE (-3100 1175);
FORCEPROP 1 LAST VALUE 0
J 2
(-3125 1175);
DISPLAY 0.489362 (-3125 1175);
PAINT SKYBLUE (-3125 1175);
FORCEPROP 2 LAST CDS_LIB pure_quanta
J 0
(-3125 1225);
DISPLAY INVISIBLE (-3125 1225);
FORCEPROP 1 LAST PATH I51
J 0
(-3175 1375);
DISPLAY 0.978723 (-3175 1375);
PAINT WHITE (-3175 1375);
DISPLAY INVISIBLE (-3175 1375);
FORCEPROP 1 LAST PART_NUMBER CS00002JB13
J 0
(-3800 1175);
DISPLAY 0.489362 (-3800 1175);
PAINT SKYBLUE (-3800 1175);
DISPLAY INVISIBLE (-3800 1175);
FORCEADD Q_RES..1
(-3125 1875);
FORCEPROP 1 LAST LOCATION PR409
J 0
(-3175 1925);
DISPLAY 0.489362 (-3175 1925);
PAINT SKYBLUE (-3175 1925);
FORCEPROP 0 LAST $SEC 1
J 0
(-3175 1975);
DISPLAY 0.680851 (-3175 1975);
PAINT MONO (-3175 1975);
DISPLAY INVISIBLE (-3175 1975);
FORCEPROP 0 LAST CDS_SEC 1
J 0
(-3175 1975);
DISPLAY 1.021277 (-3175 1975);
DISPLAY INVISIBLE (-3175 1975);
FORCEPROP 1 LASTPIN (-3225 1875) $PN 1
J 0
(-3213 1887);
DISPLAY 0.489362 (-3213 1887);
PAINT MONO (-3213 1887);
FORCEPROP 1 LASTPIN (-3025 1875) $PN 2
J 0
(-3063 1887);
DISPLAY 0.489362 (-3063 1887);
PAINT MONO (-3063 1887);
FORCEPROP 1 LAST PACK_TYPE 0402LF
J 0
(-3025 1825);
DISPLAY 0.489362 (-3025 1825);
PAINT SKYBLUE (-3025 1825);
FORCEPROP 1 LAST WATTAGE 1/16W
J 2
(-3200 1825);
DISPLAY 0.489362 (-3200 1825);
PAINT SKYBLUE (-3200 1825);
FORCEPROP 1 LAST TOLERANCE 5%
J 0
(-3100 1825);
DISPLAY 0.489362 (-3100 1825);
PAINT SKYBLUE (-3100 1825);
FORCEPROP 1 LAST VALUE 0
J 2
(-3125 1825);
DISPLAY 0.489362 (-3125 1825);
PAINT SKYBLUE (-3125 1825);
FORCEPROP 1 LAST MATERIAL CHIP
J 0
(-3450 1825);
DISPLAY 0.489362 (-3450 1825);
PAINT SKYBLUE (-3450 1825);
FORCEPROP 2 LAST CDS_LIB pure_quanta
J 0
(-3125 1875);
DISPLAY INVISIBLE (-3125 1875);
FORCEPROP 1 LAST PATH I52
J 0
(-3175 2025);
DISPLAY 0.978723 (-3175 2025);
PAINT WHITE (-3175 2025);
DISPLAY INVISIBLE (-3175 2025);
FORCEPROP 1 LAST PART_NUMBER CS00002JB13
J 0
(-3800 1825);
DISPLAY 0.489362 (-3800 1825);
PAINT SKYBLUE (-3800 1825);
DISPLAY INVISIBLE (-3800 1825);
FORCEADD UNIVERSAL_GND..1
(-2675 1150);
FORCEPROP 3 LASTPIN (-2675 1200) SIG_NAME GND\g
J 0
(-2665 1210);
DISPLAY 0.659574 (-2665 1210);
PAINT MONO (-2665 1210);
DISPLAY INVISIBLE (-2665 1210);
FORCEPROP 2 LAST CDS_LIB pure_quanta_power
J 0
(-2675 1150);
DISPLAY INVISIBLE (-2675 1150);
FORCEPROP 1 LAST HDL_POWER GND
J 1
(-2650 1075);
DISPLAY 0.872340 (-2650 1075);
PAINT GREEN (-2650 1075);
DISPLAY INVISIBLE (-2650 1075);
FORCEPROP 1 LAST PATH I53
J 0
(-2600 1150);
DISPLAY 0.872340 (-2600 1150);
PAINT AQUA (-2600 1150);
DISPLAY INVISIBLE (-2600 1150);
FORCEADD UNIVERSAL_GND..1
(-2675 1800);
FORCEPROP 3 LASTPIN (-2675 1850) SIG_NAME GND\g
J 0
(-2665 1860);
DISPLAY 0.659574 (-2665 1860);
PAINT MONO (-2665 1860);
DISPLAY INVISIBLE (-2665 1860);
FORCEPROP 2 LAST CDS_LIB pure_quanta_power
J 0
(-2675 1800);
DISPLAY INVISIBLE (-2675 1800);
FORCEPROP 1 LAST HDL_POWER GND
J 1
(-2650 1725);
DISPLAY 0.872340 (-2650 1725);
PAINT GREEN (-2650 1725);
DISPLAY INVISIBLE (-2650 1725);
FORCEPROP 1 LAST PATH I54
J 0
(-2600 1800);
DISPLAY 0.872340 (-2600 1800);
PAINT AQUA (-2600 1800);
DISPLAY INVISIBLE (-2600 1800);
FORCEADD UNIVERSAL_GND..1
(-2125 1200);
FORCEPROP 3 LASTPIN (-2125 1250) SIG_NAME GND\g
J 0
(-2115 1260);
DISPLAY 0.659574 (-2115 1260);
PAINT MONO (-2115 1260);
DISPLAY INVISIBLE (-2115 1260);
FORCEPROP 2 LAST CDS_LIB pure_quanta_power
J 0
(-2125 1200);
DISPLAY INVISIBLE (-2125 1200);
FORCEPROP 1 LAST HDL_POWER GND
J 1
(-2100 1125);
DISPLAY 0.872340 (-2100 1125);
PAINT GREEN (-2100 1125);
DISPLAY INVISIBLE (-2100 1125);
FORCEPROP 1 LAST PATH I55
J 0
(-2050 1200);
DISPLAY 0.872340 (-2050 1200);
PAINT AQUA (-2050 1200);
DISPLAY INVISIBLE (-2050 1200);
FORCEADD Q_RES..2
(-2125 1425);
FORCEPROP 1 LAST LOCATION PR390
J 0
(-2080 1550);
DISPLAY 0.489362 (-2080 1550);
PAINT SKYBLUE (-2080 1550);
FORCEPROP 0 LAST $SEC 1
J 0
(-2075 1575);
DISPLAY 0.680851 (-2075 1575);
PAINT MONO (-2075 1575);
DISPLAY INVISIBLE (-2075 1575);
FORCEPROP 0 LAST CDS_SEC 1
J 0
(-2075 1575);
DISPLAY 1.021277 (-2075 1575);
DISPLAY INVISIBLE (-2075 1575);
FORCEPROP 1 LASTPIN (-2125 1525) $PN 1
J 0
(-2120 1487);
DISPLAY 0.489362 (-2120 1487);
PAINT MONO (-2120 1487);
FORCEPROP 1 LASTPIN (-2125 1325) $PN 2
J 0
(-2120 1335);
DISPLAY 0.489362 (-2120 1335);
PAINT MONO (-2120 1335);
FORCEPROP 1 LAST MATERIAL EMPTY
J 0
(-2085 1350);
DISPLAY 0.489362 (-2085 1350);
PAINT RED (-2085 1350);
FORCEPROP 1 LAST WATTAGE 1/16W
J 0
(-2085 1400);
DISPLAY 0.489362 (-2085 1400);
PAINT SKYBLUE (-2085 1400);
FORCEPROP 1 LAST TOLERANCE 5%
J 0
(-2080 1450);
DISPLAY 0.489362 (-2080 1450);
PAINT SKYBLUE (-2080 1450);
FORCEPROP 1 LAST VALUE 0
J 0
(-2080 1500);
DISPLAY 0.489362 (-2080 1500);
PAINT SKYBLUE (-2080 1500);
FORCEPROP 1 LAST PACK_TYPE 0402LF
J 0
(-2085 1250);
DISPLAY 0.489362 (-2085 1250);
PAINT SKYBLUE (-2085 1250);
FORCEPROP 2 LAST CDS_LIB pure_quanta
J 0
(-2125 1425);
DISPLAY INVISIBLE (-2125 1425);
FORCEPROP 1 LAST PATH I56
J 0
(-2075 1600);
DISPLAY 0.978723 (-2075 1600);
PAINT WHITE (-2075 1600);
DISPLAY INVISIBLE (-2075 1600);
FORCEPROP 1 LAST PART_NUMBER CS00002JB13
J 0
(-2085 1300);
DISPLAY 0.489362 (-2085 1300);
PAINT SKYBLUE (-2085 1300);
DISPLAY INVISIBLE (-2085 1300);
FORCEADD Q_RES..1
(-3125 2325);
FORCEPROP 1 LAST LOCATION PR408
J 0
(-3175 2375);
DISPLAY 0.489362 (-3175 2375);
PAINT SKYBLUE (-3175 2375);
FORCEPROP 0 LAST $SEC 1
J 0
(-3175 2425);
DISPLAY 0.680851 (-3175 2425);
PAINT MONO (-3175 2425);
DISPLAY INVISIBLE (-3175 2425);
FORCEPROP 0 LAST CDS_SEC 1
J 0
(-3175 2425);
DISPLAY 1.021277 (-3175 2425);
DISPLAY INVISIBLE (-3175 2425);
FORCEPROP 1 LASTPIN (-3225 2325) $PN 1
J 0
(-3213 2337);
DISPLAY 0.489362 (-3213 2337);
PAINT MONO (-3213 2337);
FORCEPROP 1 LASTPIN (-3025 2325) $PN 2
J 0
(-3063 2337);
DISPLAY 0.489362 (-3063 2337);
PAINT MONO (-3063 2337);
FORCEPROP 1 LAST WATTAGE 1/16W
J 2
(-3200 2275);
DISPLAY 0.489362 (-3200 2275);
PAINT SKYBLUE (-3200 2275);
FORCEPROP 1 LAST MATERIAL CHIP
J 0
(-3450 2275);
DISPLAY 0.489362 (-3450 2275);
PAINT SKYBLUE (-3450 2275);
FORCEPROP 1 LAST TOLERANCE 5%
J 0
(-3100 2275);
DISPLAY 0.489362 (-3100 2275);
PAINT SKYBLUE (-3100 2275);
FORCEPROP 1 LAST VALUE 0
J 2
(-3125 2275);
DISPLAY 0.489362 (-3125 2275);
PAINT SKYBLUE (-3125 2275);
FORCEPROP 1 LAST PACK_TYPE 0402LF
J 0
(-3025 2275);
DISPLAY 0.489362 (-3025 2275);
PAINT SKYBLUE (-3025 2275);
FORCEPROP 2 LAST CDS_LIB pure_quanta
J 0
(-3125 2325);
DISPLAY INVISIBLE (-3125 2325);
FORCEPROP 1 LAST PATH I57
J 0
(-3175 2475);
DISPLAY 0.978723 (-3175 2475);
PAINT WHITE (-3175 2475);
DISPLAY INVISIBLE (-3175 2475);
FORCEPROP 1 LAST PART_NUMBER CS00002JB13
J 0
(-3800 2275);
DISPLAY 0.489362 (-3800 2275);
PAINT SKYBLUE (-3800 2275);
DISPLAY INVISIBLE (-3800 2275);
FORCEADD Q_RES..1
(-3125 2775);
FORCEPROP 1 LAST LOCATION PR14
J 0
(-3175 2825);
DISPLAY 0.489362 (-3175 2825);
PAINT SKYBLUE (-3175 2825);
FORCEPROP 0 LAST $SEC 1
J 0
(-3175 2875);
DISPLAY 0.680851 (-3175 2875);
PAINT MONO (-3175 2875);
DISPLAY INVISIBLE (-3175 2875);
FORCEPROP 0 LAST CDS_SEC 1
J 0
(-3175 2875);
DISPLAY 1.021277 (-3175 2875);
DISPLAY INVISIBLE (-3175 2875);
FORCEPROP 1 LASTPIN (-3225 2775) $PN 1
J 0
(-3213 2787);
DISPLAY 0.489362 (-3213 2787);
PAINT MONO (-3213 2787);
FORCEPROP 1 LASTPIN (-3025 2775) $PN 2
J 0
(-3063 2787);
DISPLAY 0.489362 (-3063 2787);
PAINT MONO (-3063 2787);
FORCEPROP 1 LAST WATTAGE 1/16W
J 2
(-3200 2725);
DISPLAY 0.489362 (-3200 2725);
PAINT SKYBLUE (-3200 2725);
FORCEPROP 1 LAST MATERIAL CHIP
J 0
(-3450 2725);
DISPLAY 0.489362 (-3450 2725);
PAINT SKYBLUE (-3450 2725);
FORCEPROP 1 LAST TOLERANCE 5%
J 0
(-3100 2725);
DISPLAY 0.489362 (-3100 2725);
PAINT SKYBLUE (-3100 2725);
FORCEPROP 1 LAST VALUE 0
J 2
(-3125 2725);
DISPLAY 0.489362 (-3125 2725);
PAINT SKYBLUE (-3125 2725);
FORCEPROP 1 LAST PACK_TYPE 0402LF
J 0
(-3025 2725);
DISPLAY 0.489362 (-3025 2725);
PAINT SKYBLUE (-3025 2725);
FORCEPROP 2 LAST CDS_LIB pure_quanta
J 0
(-3125 2775);
DISPLAY INVISIBLE (-3125 2775);
FORCEPROP 1 LAST PATH I58
J 0
(-3175 2925);
DISPLAY 0.978723 (-3175 2925);
PAINT WHITE (-3175 2925);
DISPLAY INVISIBLE (-3175 2925);
FORCEPROP 1 LAST PART_NUMBER CS00002JB13
J 0
(-3800 2725);
DISPLAY 0.489362 (-3800 2725);
PAINT SKYBLUE (-3800 2725);
DISPLAY INVISIBLE (-3800 2725);
FORCEADD Q_RES..1
(-3125 3225);
FORCEPROP 1 LAST LOCATION PR13
J 0
(-3175 3275);
DISPLAY 0.489362 (-3175 3275);
PAINT SKYBLUE (-3175 3275);
FORCEPROP 0 LAST $SEC 1
J 0
(-3175 3325);
DISPLAY 0.680851 (-3175 3325);
PAINT MONO (-3175 3325);
DISPLAY INVISIBLE (-3175 3325);
FORCEPROP 0 LAST CDS_SEC 1
J 0
(-3175 3325);
DISPLAY 1.021277 (-3175 3325);
DISPLAY INVISIBLE (-3175 3325);
FORCEPROP 1 LASTPIN (-3225 3225) $PN 1
J 0
(-3213 3237);
DISPLAY 0.489362 (-3213 3237);
PAINT MONO (-3213 3237);
FORCEPROP 1 LASTPIN (-3025 3225) $PN 2
J 0
(-3063 3237);
DISPLAY 0.489362 (-3063 3237);
PAINT MONO (-3063 3237);
FORCEPROP 1 LAST MATERIAL CHIP
J 0
(-3450 3175);
DISPLAY 0.489362 (-3450 3175);
PAINT SKYBLUE (-3450 3175);
FORCEPROP 1 LAST WATTAGE 1/16W
J 2
(-3200 3175);
DISPLAY 0.489362 (-3200 3175);
PAINT SKYBLUE (-3200 3175);
FORCEPROP 1 LAST TOLERANCE 5%
J 0
(-3100 3175);
DISPLAY 0.489362 (-3100 3175);
PAINT SKYBLUE (-3100 3175);
FORCEPROP 1 LAST VALUE 0
J 2
(-3125 3175);
DISPLAY 0.489362 (-3125 3175);
PAINT SKYBLUE (-3125 3175);
FORCEPROP 1 LAST PACK_TYPE 0402LF
J 0
(-3025 3175);
DISPLAY 0.489362 (-3025 3175);
PAINT SKYBLUE (-3025 3175);
FORCEPROP 2 LAST CDS_LIB pure_quanta
J 0
(-3125 3225);
DISPLAY INVISIBLE (-3125 3225);
FORCEPROP 1 LAST PATH I59
J 0
(-3175 3375);
DISPLAY 0.978723 (-3175 3375);
PAINT WHITE (-3175 3375);
DISPLAY INVISIBLE (-3175 3375);
FORCEPROP 1 LAST PART_NUMBER CS00002JB13
J 0
(-3800 3175);
DISPLAY 0.489362 (-3800 3175);
PAINT SKYBLUE (-3800 3175);
DISPLAY INVISIBLE (-3800 3175);
FORCEADD Q_RES..2
(-6525 675);
FORCEPROP 1 LAST LOCATION PR6
J 0
(-6475 775);
DISPLAY 0.489362 (-6475 775);
PAINT SKYBLUE (-6475 775);
FORCEPROP 2 LAST SEC 1
J 0
(-6475 900);
DISPLAY 0.680851 (-6475 900);
PAINT MONO (-6475 900);
DISPLAY INVISIBLE (-6475 900);
FORCEPROP 1 LASTPIN (-6525 775) $PN 1
J 0
(-6520 737);
DISPLAY 0.489362 (-6520 737);
PAINT MONO (-6520 737);
FORCEPROP 1 LASTPIN (-6525 575) $PN 2
J 0
(-6520 585);
DISPLAY 0.489362 (-6520 585);
PAINT MONO (-6520 585);
FORCEPROP 1 LAST WATTAGE 1/16W
J 0
(-6475 625);
DISPLAY 0.489362 (-6475 625);
PAINT SKYBLUE (-6475 625);
FORCEPROP 1 LAST MATERIAL CHIP
J 0
(-6475 575);
DISPLAY 0.489362 (-6475 575);
PAINT SKYBLUE (-6475 575);
FORCEPROP 1 LAST TOLERANCE 1%
J 0
(-6475 675);
DISPLAY 0.489362 (-6475 675);
PAINT SKYBLUE (-6475 675);
FORCEPROP 1 LAST VALUE 10K
J 0
(-6475 725);
DISPLAY 0.489362 (-6475 725);
PAINT SKYBLUE (-6475 725);
FORCEPROP 1 LAST PACK_TYPE 0402LF
J 0
(-6475 475);
DISPLAY 0.489362 (-6475 475);
PAINT SKYBLUE (-6475 475);
FORCEPROP 2 LAST SEC_TYPE 0402LF
J 0
(-6475 900);
DISPLAY 1.021277 (-6475 900);
DISPLAY INVISIBLE (-6475 900);
FORCEPROP 2 LAST CDS_LIB pure_quanta
J 0
(-6525 675);
DISPLAY INVISIBLE (-6525 675);
FORCEPROP 1 LAST PATH I6
J 0
(-6475 850);
DISPLAY 0.978723 (-6475 850);
PAINT WHITE (-6475 850);
DISPLAY INVISIBLE (-6475 850);
FORCEPROP 1 LAST PART_NUMBER CS31002FB08
J 0
(-6475 525);
DISPLAY 0.489362 (-6475 525);
PAINT SKYBLUE (-6475 525);
DISPLAY INVISIBLE (-6475 525);
FORCEADD Q_RES..1
(-3125 3675);
FORCEPROP 1 LAST LOCATION PR407
J 0
(-3175 3725);
DISPLAY 0.489362 (-3175 3725);
PAINT SKYBLUE (-3175 3725);
FORCEPROP 0 LAST $SEC 1
J 0
(-3175 3775);
DISPLAY 0.680851 (-3175 3775);
PAINT MONO (-3175 3775);
DISPLAY INVISIBLE (-3175 3775);
FORCEPROP 0 LAST CDS_SEC 1
J 0
(-3175 3775);
DISPLAY 1.021277 (-3175 3775);
DISPLAY INVISIBLE (-3175 3775);
FORCEPROP 1 LASTPIN (-3225 3675) $PN 1
J 0
(-3213 3687);
DISPLAY 0.489362 (-3213 3687);
PAINT MONO (-3213 3687);
FORCEPROP 1 LASTPIN (-3025 3675) $PN 2
J 0
(-3063 3687);
DISPLAY 0.489362 (-3063 3687);
PAINT MONO (-3063 3687);
FORCEPROP 1 LAST VALUE 0
J 2
(-3125 3625);
DISPLAY 0.489362 (-3125 3625);
PAINT SKYBLUE (-3125 3625);
FORCEPROP 1 LAST WATTAGE 1/16W
J 2
(-3200 3625);
DISPLAY 0.489362 (-3200 3625);
PAINT SKYBLUE (-3200 3625);
FORCEPROP 1 LAST MATERIAL CHIP
J 0
(-3450 3625);
DISPLAY 0.489362 (-3450 3625);
PAINT SKYBLUE (-3450 3625);
FORCEPROP 1 LAST PACK_TYPE 0402LF
J 0
(-3025 3625);
DISPLAY 0.489362 (-3025 3625);
PAINT SKYBLUE (-3025 3625);
FORCEPROP 1 LAST TOLERANCE 5%
J 0
(-3100 3625);
DISPLAY 0.489362 (-3100 3625);
PAINT SKYBLUE (-3100 3625);
FORCEPROP 2 LAST CDS_LIB pure_quanta
J 0
(-3125 3675);
DISPLAY INVISIBLE (-3125 3675);
FORCEPROP 1 LAST PATH I60
J 0
(-3175 3825);
DISPLAY 0.978723 (-3175 3825);
PAINT WHITE (-3175 3825);
DISPLAY INVISIBLE (-3175 3825);
FORCEPROP 1 LAST PART_NUMBER CS00002JB13
J 0
(-3800 3625);
DISPLAY 0.489362 (-3800 3625);
PAINT SKYBLUE (-3800 3625);
DISPLAY INVISIBLE (-3800 3625);
FORCEADD UNIVERSAL_GND..1
(-2675 2250);
FORCEPROP 3 LASTPIN (-2675 2300) SIG_NAME GND\g
J 0
(-2665 2310);
DISPLAY 0.659574 (-2665 2310);
PAINT MONO (-2665 2310);
DISPLAY INVISIBLE (-2665 2310);
FORCEPROP 2 LAST CDS_LIB pure_quanta_power
J 0
(-2675 2250);
DISPLAY INVISIBLE (-2675 2250);
FORCEPROP 1 LAST HDL_POWER GND
J 1
(-2650 2175);
DISPLAY 0.872340 (-2650 2175);
PAINT GREEN (-2650 2175);
DISPLAY INVISIBLE (-2650 2175);
FORCEPROP 1 LAST PATH I61
J 0
(-2600 2250);
DISPLAY 0.872340 (-2600 2250);
PAINT AQUA (-2600 2250);
DISPLAY INVISIBLE (-2600 2250);
FORCEADD UNIVERSAL_GND..1
(-2675 2700);
FORCEPROP 3 LASTPIN (-2675 2750) SIG_NAME GND\g
J 0
(-2665 2760);
DISPLAY 0.659574 (-2665 2760);
PAINT MONO (-2665 2760);
DISPLAY INVISIBLE (-2665 2760);
FORCEPROP 2 LAST CDS_LIB pure_quanta_power
J 0
(-2675 2700);
DISPLAY INVISIBLE (-2675 2700);
FORCEPROP 1 LAST HDL_POWER GND
J 1
(-2650 2625);
DISPLAY 0.872340 (-2650 2625);
PAINT GREEN (-2650 2625);
DISPLAY INVISIBLE (-2650 2625);
FORCEPROP 1 LAST PATH I62
J 0
(-2600 2700);
DISPLAY 0.872340 (-2600 2700);
PAINT AQUA (-2600 2700);
DISPLAY INVISIBLE (-2600 2700);
FORCEADD UNIVERSAL_GND..1
(-2675 3150);
FORCEPROP 3 LASTPIN (-2675 3200) SIG_NAME GND\g
J 0
(-2665 3210);
DISPLAY 0.659574 (-2665 3210);
PAINT MONO (-2665 3210);
DISPLAY INVISIBLE (-2665 3210);
FORCEPROP 2 LAST CDS_LIB pure_quanta_power
J 0
(-2675 3150);
DISPLAY INVISIBLE (-2675 3150);
FORCEPROP 1 LAST HDL_POWER GND
J 1
(-2650 3075);
DISPLAY 0.872340 (-2650 3075);
PAINT GREEN (-2650 3075);
DISPLAY INVISIBLE (-2650 3075);
FORCEPROP 1 LAST PATH I63
J 0
(-2600 3150);
DISPLAY 0.872340 (-2600 3150);
PAINT AQUA (-2600 3150);
DISPLAY INVISIBLE (-2600 3150);
FORCEADD UNIVERSAL_GND..1
(-2675 3600);
FORCEPROP 3 LASTPIN (-2675 3650) SIG_NAME GND\g
J 0
(-2665 3660);
DISPLAY 0.659574 (-2665 3660);
PAINT MONO (-2665 3660);
DISPLAY INVISIBLE (-2665 3660);
FORCEPROP 2 LAST CDS_LIB pure_quanta_power
J 0
(-2675 3600);
DISPLAY INVISIBLE (-2675 3600);
FORCEPROP 1 LAST HDL_POWER GND
J 1
(-2650 3525);
DISPLAY 0.872340 (-2650 3525);
PAINT GREEN (-2650 3525);
DISPLAY INVISIBLE (-2650 3525);
FORCEPROP 1 LAST PATH I64
J 0
(-2600 3600);
DISPLAY 0.872340 (-2600 3600);
PAINT AQUA (-2600 3600);
DISPLAY INVISIBLE (-2600 3600);
FORCEADD UNIVERSAL_GND..1
(-2675 4050);
FORCEPROP 3 LASTPIN (-2675 4100) SIG_NAME GND\g
J 0
(-2665 4110);
DISPLAY 0.659574 (-2665 4110);
PAINT MONO (-2665 4110);
DISPLAY INVISIBLE (-2665 4110);
FORCEPROP 2 LAST CDS_LIB pure_quanta_power
J 0
(-2675 4050);
DISPLAY INVISIBLE (-2675 4050);
FORCEPROP 1 LAST HDL_POWER GND
J 1
(-2650 3975);
DISPLAY 0.872340 (-2650 3975);
PAINT GREEN (-2650 3975);
DISPLAY INVISIBLE (-2650 3975);
FORCEPROP 1 LAST PATH I65
J 0
(-2600 4050);
DISPLAY 0.872340 (-2600 4050);
PAINT AQUA (-2600 4050);
DISPLAY INVISIBLE (-2600 4050);
FORCEADD Q_RES..1
(-1650 1625);
FORCEPROP 1 LAST LOCATION PR392
J 0
(-1700 1675);
DISPLAY 0.489362 (-1700 1675);
PAINT SKYBLUE (-1700 1675);
FORCEPROP 0 LAST $SEC 1
J 0
(-1700 1700);
DISPLAY 0.680851 (-1700 1700);
PAINT MONO (-1700 1700);
DISPLAY INVISIBLE (-1700 1700);
FORCEPROP 0 LAST CDS_SEC 1
J 0
(-1700 1700);
DISPLAY 1.021277 (-1700 1700);
DISPLAY INVISIBLE (-1700 1700);
FORCEPROP 1 LASTPIN (-1750 1625) $PN 1
J 0
(-1738 1637);
DISPLAY 0.489362 (-1738 1637);
PAINT MONO (-1738 1637);
FORCEPROP 1 LASTPIN (-1550 1625) $PN 2
J 0
(-1588 1637);
DISPLAY 0.489362 (-1588 1637);
PAINT MONO (-1588 1637);
FORCEPROP 1 LAST WATTAGE 1/16W
J 0
(-1550 1575);
DISPLAY 0.489362 (-1550 1575);
PAINT SKYBLUE (-1550 1575);
FORCEPROP 1 LAST MATERIAL EMPTY
J 0
(-1900 1550);
DISPLAY 0.489362 (-1900 1550);
PAINT RED (-1900 1550);
FORCEPROP 1 LAST TOLERANCE 5%
J 0
(-1525 1650);
DISPLAY 0.489362 (-1525 1650);
PAINT SKYBLUE (-1525 1650);
FORCEPROP 1 LAST VALUE 0
J 2
(-1775 1650);
DISPLAY 0.489362 (-1775 1650);
PAINT SKYBLUE (-1775 1650);
FORCEPROP 1 LAST PACK_TYPE 0402LF
J 0
(-1550 1550);
DISPLAY 0.489362 (-1550 1550);
PAINT SKYBLUE (-1550 1550);
FORCEPROP 2 LAST CDS_LIB pure_quanta
J 0
(-1650 1625);
DISPLAY INVISIBLE (-1650 1625);
FORCEPROP 1 LAST PATH I66
J 0
(-1700 1775);
DISPLAY 0.978723 (-1700 1775);
PAINT WHITE (-1700 1775);
DISPLAY INVISIBLE (-1700 1775);
FORCEPROP 1 LAST PART_NUMBER CS00002JB13
J 0
(-1900 1575);
DISPLAY 0.489362 (-1900 1575);
PAINT SKYBLUE (-1900 1575);
DISPLAY INVISIBLE (-1900 1575);
FORCEADD Q_RES..1
(-1700 1850);
FORCEPROP 1 LAST LOCATION PR391
J 0
(-1750 1900);
DISPLAY 0.489362 (-1750 1900);
PAINT SKYBLUE (-1750 1900);
FORCEPROP 0 LAST $SEC 1
J 0
(-1750 1925);
DISPLAY 0.680851 (-1750 1925);
PAINT MONO (-1750 1925);
DISPLAY INVISIBLE (-1750 1925);
FORCEPROP 0 LAST CDS_SEC 1
J 0
(-1650 2025);
DISPLAY 1.021277 (-1650 2025);
DISPLAY INVISIBLE (-1650 2025);
FORCEPROP 1 LASTPIN (-1800 1850) $PN 1
J 0
(-1788 1862);
DISPLAY 0.489362 (-1788 1862);
PAINT MONO (-1788 1862);
FORCEPROP 1 LASTPIN (-1600 1850) $PN 2
J 0
(-1638 1862);
DISPLAY 0.489362 (-1638 1862);
PAINT MONO (-1638 1862);
FORCEPROP 1 LAST PACK_TYPE 0402LF
J 0
(-1525 1800);
DISPLAY 0.489362 (-1525 1800);
PAINT SKYBLUE (-1525 1800);
FORCEPROP 1 LAST WATTAGE 1/16W
J 0
(-1525 1775);
DISPLAY 0.489362 (-1525 1775);
PAINT SKYBLUE (-1525 1775);
FORCEPROP 1 LAST MATERIAL EMPTY
J 0
(-1925 1775);
DISPLAY 0.489362 (-1925 1775);
PAINT RED (-1925 1775);
FORCEPROP 1 LAST TOLERANCE 1%
J 0
(-1575 1875);
DISPLAY 0.489362 (-1575 1875);
PAINT SKYBLUE (-1575 1875);
FORCEPROP 1 LAST VALUE 1K
J 2
(-1825 1875);
DISPLAY 0.489362 (-1825 1875);
PAINT SKYBLUE (-1825 1875);
FORCEPROP 2 LAST CDS_LIB pure_quanta
J 0
(-1700 1850);
DISPLAY INVISIBLE (-1700 1850);
FORCEPROP 1 LAST PATH I67
J 0
(-1750 2000);
DISPLAY 0.978723 (-1750 2000);
PAINT WHITE (-1750 2000);
DISPLAY INVISIBLE (-1750 2000);
FORCEPROP 1 LAST PART_NUMBER CS21002FB06
J 0
(-1925 1800);
DISPLAY 0.489362 (-1925 1800);
PAINT SKYBLUE (-1925 1800);
DISPLAY INVISIBLE (-1925 1800);
FORCEADD VCC_CORE..1
(-1350 2000);
FORCEPROP 3 LASTPIN (-1350 1950) SIG_NAME PVDD18_S5_P1\g
J 0
(-1340 1960);
DISPLAY 0.659574 (-1340 1960);
PAINT MONO (-1340 1960);
DISPLAY INVISIBLE (-1340 1960);
FORCEPROP 1 LAST HDL_POWER PVDD18_S5_P1
J 1
(-1350 2050);
DISPLAY 0.489362 (-1350 2050);
PAINT GREEN (-1350 2050);
FORCEPROP 2 LAST CDS_LIB pure_quanta_power
J 0
(-1350 2000);
DISPLAY INVISIBLE (-1350 2000);
FORCEPROP 1 LAST PATH I68
J 0
(-1300 2025);
DISPLAY 0.872340 (-1300 2025);
PAINT AQUA (-1300 2025);
DISPLAY INVISIBLE (-1300 2025);
FORCEADD OFFPAGE..4
(-750 1625);
FORCEPROP 2 LAST $XR0 81 
J 0
(-564 1625);
DISPLAY 0.638298 (-564 1625);
PAINT MONO (-564 1625);
FORCEPROP 2 LAST CDS_LIB standard
J 2
(-750 1625);
DISPLAY INVISIBLE (-750 1625);
FORCEPROP 1 LAST OFFPAGE TRUE
J 0
(-425 1500);
DISPLAY 0.872340 (-425 1500);
PAINT GREEN (-425 1500);
DISPLAY INVISIBLE (-425 1500);
FORCEPROP 1 LAST COMMENT_BODY TRUE
J 0
(-775 1525);
DISPLAY 0.872340 (-775 1525);
PAINT GREEN (-775 1525);
DISPLAY INVISIBLE (-775 1525);
FORCEPROP 2 LAST PATH I69
J 0
(-550 1675);
DISPLAY 0.680851 (-550 1675);
DISPLAY INVISIBLE (-550 1675);
FORCEADD VCC_CORE..1
(-6275 750);
FORCEPROP 3 LASTPIN (-6275 700) SIG_NAME P12V_AUX\g
J 0
(-6265 710);
DISPLAY 0.659574 (-6265 710);
PAINT MONO (-6265 710);
DISPLAY INVISIBLE (-6265 710);
FORCEPROP 1 LAST HDL_POWER P12V_AUX
J 1
(-6275 800);
DISPLAY 0.489362 (-6275 800);
PAINT GREEN (-6275 800);
FORCEPROP 2 LAST CDS_LIB pure_quanta_power
J 0
(-6275 750);
DISPLAY INVISIBLE (-6275 750);
FORCEPROP 1 LAST PATH I7
J 0
(-6225 775);
DISPLAY 0.872340 (-6225 775);
PAINT AQUA (-6225 775);
DISPLAY INVISIBLE (-6225 775);
FORCEADD Q_RES..1
(-3125 4125);
FORCEPROP 1 LAST LOCATION PR406
J 0
(-3175 4175);
DISPLAY 0.489362 (-3175 4175);
PAINT SKYBLUE (-3175 4175);
FORCEPROP 0 LAST $SEC 1
J 0
(-3175 4225);
DISPLAY 0.680851 (-3175 4225);
PAINT MONO (-3175 4225);
DISPLAY INVISIBLE (-3175 4225);
FORCEPROP 0 LAST CDS_SEC 1
J 0
(-3175 4225);
DISPLAY 1.021277 (-3175 4225);
DISPLAY INVISIBLE (-3175 4225);
FORCEPROP 1 LASTPIN (-3225 4125) $PN 1
J 0
(-3213 4137);
DISPLAY 0.489362 (-3213 4137);
PAINT MONO (-3213 4137);
FORCEPROP 1 LASTPIN (-3025 4125) $PN 2
J 0
(-3063 4137);
DISPLAY 0.489362 (-3063 4137);
PAINT MONO (-3063 4137);
FORCEPROP 1 LAST VALUE 0
J 2
(-3125 4075);
DISPLAY 0.489362 (-3125 4075);
PAINT SKYBLUE (-3125 4075);
FORCEPROP 1 LAST MATERIAL CHIP
J 0
(-3450 4075);
DISPLAY 0.489362 (-3450 4075);
PAINT SKYBLUE (-3450 4075);
FORCEPROP 1 LAST WATTAGE 1/16W
J 2
(-3200 4075);
DISPLAY 0.489362 (-3200 4075);
PAINT SKYBLUE (-3200 4075);
FORCEPROP 1 LAST TOLERANCE 5%
J 0
(-3100 4075);
DISPLAY 0.489362 (-3100 4075);
PAINT SKYBLUE (-3100 4075);
FORCEPROP 1 LAST PACK_TYPE 0402LF
J 0
(-3025 4075);
DISPLAY 0.489362 (-3025 4075);
PAINT SKYBLUE (-3025 4075);
FORCEPROP 2 LAST CDS_LIB pure_quanta
J 0
(-3125 4125);
DISPLAY INVISIBLE (-3125 4125);
FORCEPROP 1 LAST PATH I70
J 0
(-3175 4275);
DISPLAY 0.978723 (-3175 4275);
PAINT WHITE (-3175 4275);
DISPLAY INVISIBLE (-3175 4275);
FORCEPROP 1 LAST PART_NUMBER CS00002JB13
J 0
(-3800 4075);
DISPLAY 0.489362 (-3800 4075);
PAINT SKYBLUE (-3800 4075);
DISPLAY INVISIBLE (-3800 4075);
FORCEADD UNIVERSAL_GND..1
(-3375 5450);
FORCEPROP 3 LASTPIN (-3375 5500) SIG_NAME GND\g
J 0
(-3365 5510);
DISPLAY 0.659574 (-3365 5510);
PAINT MONO (-3365 5510);
DISPLAY INVISIBLE (-3365 5510);
FORCEPROP 2 LAST CDS_LIB pure_quanta_power
J 0
(-3375 5450);
DISPLAY INVISIBLE (-3375 5450);
FORCEPROP 1 LAST HDL_POWER GND
J 1
(-3350 5375);
DISPLAY 0.872340 (-3350 5375);
PAINT GREEN (-3350 5375);
DISPLAY INVISIBLE (-3350 5375);
FORCEPROP 1 LAST PATH I71
J 0
(-3300 5450);
DISPLAY 0.872340 (-3300 5450);
PAINT AQUA (-3300 5450);
DISPLAY INVISIBLE (-3300 5450);
FORCEADD Q_CAP..1
(-3375 5675);
FORCEPROP 1 LAST LOCATION PC96
J 0
(-3325 5775);
DISPLAY 0.489362 (-3325 5775);
PAINT SKYBLUE (-3325 5775);
FORCEPROP 0 LAST $SEC 1
J 0
(-3325 5800);
DISPLAY 0.680851 (-3325 5800);
PAINT MONO (-3325 5800);
DISPLAY INVISIBLE (-3325 5800);
FORCEPROP 0 LAST CDS_SEC 1
J 0
(-3325 5800);
DISPLAY 1.021277 (-3325 5800);
DISPLAY INVISIBLE (-3325 5800);
FORCEPROP 1 LASTPIN (-3375 5775) $PN 1
J 0
(-3365 5755);
DISPLAY 0.489362 (-3365 5755);
PAINT MONO (-3365 5755);
FORCEPROP 1 LASTPIN (-3375 5575) $PN 2
J 0
(-3365 5555);
DISPLAY 0.489362 (-3365 5555);
PAINT MONO (-3365 5555);
FORCEPROP 1 LAST PACK_TYPE 0402
J 0
(-3325 5475);
DISPLAY 0.489362 (-3325 5475);
PAINT SKYBLUE (-3325 5475);
FORCEPROP 1 LAST VOLTAGE 25V
J 0
(-3325 5675);
DISPLAY 0.489362 (-3325 5675);
PAINT SKYBLUE (-3325 5675);
FORCEPROP 1 LAST VALUE 0.1UF
J 0
(-3325 5725);
DISPLAY 0.489362 (-3325 5725);
PAINT SKYBLUE (-3325 5725);
FORCEPROP 1 LAST TOLERANCE 10%
J 0
(-3325 5625);
DISPLAY 0.489362 (-3325 5625);
PAINT SKYBLUE (-3325 5625);
FORCEPROP 1 LAST MATERIAL X7R
J 0
(-3325 5575);
DISPLAY 0.489362 (-3325 5575);
PAINT SKYBLUE (-3325 5575);
FORCEPROP 2 LAST CDS_LIB pure_quanta
J 0
(-3375 5675);
DISPLAY INVISIBLE (-3375 5675);
FORCEPROP 1 LAST PATH I72
J 0
(-3325 5825);
DISPLAY 0.978723 (-3325 5825);
PAINT WHITE (-3325 5825);
DISPLAY INVISIBLE (-3325 5825);
FORCEPROP 1 LAST PART_NUMBER CH4104K1B00
J 0
(-3325 5525);
DISPLAY 0.489362 (-3325 5525);
PAINT SKYBLUE (-3325 5525);
DISPLAY INVISIBLE (-3325 5525);
FORCEADD Q_CAP..1
(-3375 6150);
FORCEPROP 1 LAST LOCATION PC95
J 0
(-3325 6250);
DISPLAY 0.489362 (-3325 6250);
PAINT SKYBLUE (-3325 6250);
FORCEPROP 0 LAST $SEC 1
J 0
(-3325 6275);
DISPLAY 0.680851 (-3325 6275);
PAINT MONO (-3325 6275);
DISPLAY INVISIBLE (-3325 6275);
FORCEPROP 0 LAST CDS_SEC 1
J 0
(-3325 6275);
DISPLAY 1.021277 (-3325 6275);
DISPLAY INVISIBLE (-3325 6275);
FORCEPROP 1 LASTPIN (-3375 6250) $PN 1
J 0
(-3365 6230);
DISPLAY 0.489362 (-3365 6230);
PAINT MONO (-3365 6230);
FORCEPROP 1 LASTPIN (-3375 6050) $PN 2
J 0
(-3365 6030);
DISPLAY 0.489362 (-3365 6030);
PAINT MONO (-3365 6030);
FORCEPROP 1 LAST PACK_TYPE 0402
J 0
(-3325 5950);
DISPLAY 0.489362 (-3325 5950);
PAINT SKYBLUE (-3325 5950);
FORCEPROP 1 LAST VOLTAGE 25V
J 0
(-3325 6150);
DISPLAY 0.489362 (-3325 6150);
PAINT SKYBLUE (-3325 6150);
FORCEPROP 1 LAST VALUE 0.1UF
J 0
(-3325 6200);
DISPLAY 0.489362 (-3325 6200);
PAINT SKYBLUE (-3325 6200);
FORCEPROP 1 LAST TOLERANCE 10%
J 0
(-3325 6100);
DISPLAY 0.489362 (-3325 6100);
PAINT SKYBLUE (-3325 6100);
FORCEPROP 1 LAST MATERIAL X7R
J 0
(-3325 6050);
DISPLAY 0.489362 (-3325 6050);
PAINT SKYBLUE (-3325 6050);
FORCEPROP 2 LAST CDS_LIB pure_quanta
J 0
(-3375 6150);
DISPLAY INVISIBLE (-3375 6150);
FORCEPROP 1 LAST PATH I73
J 0
(-3325 6300);
DISPLAY 0.978723 (-3325 6300);
PAINT WHITE (-3325 6300);
DISPLAY INVISIBLE (-3325 6300);
FORCEPROP 1 LAST PART_NUMBER CH4104K1B00
J 0
(-3325 6000);
DISPLAY 0.489362 (-3325 6000);
PAINT SKYBLUE (-3325 6000);
DISPLAY INVISIBLE (-3325 6000);
FORCEADD UNIVERSAL_GND..1
(-3375 5900);
FORCEPROP 3 LASTPIN (-3375 5950) SIG_NAME GND\g
J 0
(-3365 5960);
DISPLAY 0.659574 (-3365 5960);
PAINT MONO (-3365 5960);
DISPLAY INVISIBLE (-3365 5960);
FORCEPROP 2 LAST CDS_LIB pure_quanta_power
J 0
(-3375 5900);
DISPLAY INVISIBLE (-3375 5900);
FORCEPROP 1 LAST HDL_POWER GND
J 1
(-3350 5825);
DISPLAY 0.872340 (-3350 5825);
PAINT GREEN (-3350 5825);
DISPLAY INVISIBLE (-3350 5825);
FORCEPROP 1 LAST PATH I74
J 0
(-3300 5900);
DISPLAY 0.872340 (-3300 5900);
PAINT AQUA (-3300 5900);
DISPLAY INVISIBLE (-3300 5900);
FORCEADD OFFPAGE..4
(-2975 4575);
FORCEPROP 2 LAST $XR0 225 
J 0
(-2789 4575);
DISPLAY 0.638298 (-2789 4575);
PAINT MONO (-2789 4575);
FORCEPROP 2 LAST CDS_LIB standard
J 0
(-2975 4575);
DISPLAY INVISIBLE (-2975 4575);
FORCEPROP 1 LAST OFFPAGE TRUE
J 0
(-2650 4450);
DISPLAY 0.872340 (-2650 4450);
PAINT GREEN (-2650 4450);
DISPLAY INVISIBLE (-2650 4450);
FORCEPROP 1 LAST COMMENT_BODY TRUE
J 0
(-3000 4475);
DISPLAY 0.872340 (-3000 4475);
PAINT GREEN (-3000 4475);
DISPLAY INVISIBLE (-3000 4475);
FORCEPROP 2 LAST PATH I75
J 0
(-2775 4625);
DISPLAY 0.680851 (-2775 4625);
DISPLAY INVISIBLE (-2775 4625);
FORCEADD OFFPAGE..2
(-2975 4675);
FORCEPROP 2 LAST $XR0 225 
J 0
(-2786 4675);
DISPLAY 0.638298 (-2786 4675);
PAINT MONO (-2786 4675);
FORCEPROP 2 LAST CDS_LIB standard
J 0
(-2975 4675);
DISPLAY INVISIBLE (-2975 4675);
FORCEPROP 1 LAST OFFPAGE TRUE
J 0
(-2650 4550);
DISPLAY 0.872340 (-2650 4550);
PAINT GREEN (-2650 4550);
DISPLAY INVISIBLE (-2650 4550);
FORCEPROP 1 LAST COMMENT_BODY TRUE
J 0
(-3020 4580);
DISPLAY 0.872340 (-3020 4580);
PAINT GREEN (-3020 4580);
DISPLAY INVISIBLE (-3020 4580);
FORCEPROP 2 LAST PATH I76
J 0
(-2775 4725);
DISPLAY 0.680851 (-2775 4725);
DISPLAY INVISIBLE (-2775 4725);
FORCEADD OFFPAGE..4
(-2975 5025);
FORCEPROP 2 LAST $XR0 225 
J 0
(-2789 5025);
DISPLAY 0.638298 (-2789 5025);
PAINT MONO (-2789 5025);
FORCEPROP 2 LAST CDS_LIB standard
J 0
(-2975 5025);
DISPLAY INVISIBLE (-2975 5025);
FORCEPROP 1 LAST OFFPAGE TRUE
J 0
(-2650 4900);
DISPLAY 0.872340 (-2650 4900);
PAINT GREEN (-2650 4900);
DISPLAY INVISIBLE (-2650 4900);
FORCEPROP 1 LAST COMMENT_BODY TRUE
J 0
(-3000 4925);
DISPLAY 0.872340 (-3000 4925);
PAINT GREEN (-3000 4925);
DISPLAY INVISIBLE (-3000 4925);
FORCEPROP 2 LAST PATH I77
J 0
(-2775 5075);
DISPLAY 0.680851 (-2775 5075);
DISPLAY INVISIBLE (-2775 5075);
FORCEADD OFFPAGE..2
(-2975 5125);
FORCEPROP 2 LAST $XR0 225 
J 0
(-2786 5125);
DISPLAY 0.638298 (-2786 5125);
PAINT MONO (-2786 5125);
FORCEPROP 2 LAST CDS_LIB standard
J 0
(-2975 5125);
DISPLAY INVISIBLE (-2975 5125);
FORCEPROP 1 LAST OFFPAGE TRUE
J 0
(-2650 5000);
DISPLAY 0.872340 (-2650 5000);
PAINT GREEN (-2650 5000);
DISPLAY INVISIBLE (-2650 5000);
FORCEPROP 1 LAST COMMENT_BODY TRUE
J 0
(-3020 5030);
DISPLAY 0.872340 (-3020 5030);
PAINT GREEN (-3020 5030);
DISPLAY INVISIBLE (-3020 5030);
FORCEPROP 2 LAST PATH I78
J 0
(-2775 5175);
DISPLAY 0.680851 (-2775 5175);
DISPLAY INVISIBLE (-2775 5175);
FORCEADD UNIVERSAL_GND..1
(-3000 5450);
FORCEPROP 3 LASTPIN (-3000 5500) SIG_NAME GND\g
J 0
(-2990 5510);
DISPLAY 0.659574 (-2990 5510);
PAINT MONO (-2990 5510);
DISPLAY INVISIBLE (-2990 5510);
FORCEPROP 2 LAST CDS_LIB pure_quanta_power
J 0
(-3000 5450);
DISPLAY INVISIBLE (-3000 5450);
FORCEPROP 1 LAST HDL_POWER GND
J 1
(-2975 5375);
DISPLAY 0.872340 (-2975 5375);
PAINT GREEN (-2975 5375);
DISPLAY INVISIBLE (-2975 5375);
FORCEPROP 1 LAST PATH I79
J 0
(-2925 5450);
DISPLAY 0.872340 (-2925 5450);
PAINT AQUA (-2925 5450);
DISPLAY INVISIBLE (-2925 5450);
FORCEADD VCC_CORE..1
(-6600 1850);
FORCEPROP 3 LASTPIN (-6600 1800) SIG_NAME P3V3_AUX\g
J 0
(-6590 1810);
DISPLAY 0.659574 (-6590 1810);
PAINT MONO (-6590 1810);
DISPLAY INVISIBLE (-6590 1810);
FORCEPROP 1 LAST HDL_POWER P3V3_AUX
J 1
(-6600 1900);
DISPLAY 0.489362 (-6600 1900);
PAINT GREEN (-6600 1900);
FORCEPROP 2 LAST CDS_LIB pure_quanta_power
J 0
(-6600 1850);
DISPLAY INVISIBLE (-6600 1850);
FORCEPROP 1 LAST PATH I8
J 0
(-6550 1875);
DISPLAY 0.872340 (-6550 1875);
PAINT AQUA (-6550 1875);
DISPLAY INVISIBLE (-6550 1875);
FORCEADD Q_CAP..1
(-3000 5675);
FORCEPROP 1 LAST LOCATION PC644
J 0
(-2950 5775);
DISPLAY 0.489362 (-2950 5775);
PAINT SKYBLUE (-2950 5775);
FORCEPROP 0 LAST $SEC 1
J 0
(-2950 5800);
DISPLAY 0.680851 (-2950 5800);
PAINT MONO (-2950 5800);
DISPLAY INVISIBLE (-2950 5800);
FORCEPROP 0 LAST CDS_SEC 1
J 0
(-2950 5800);
DISPLAY 1.021277 (-2950 5800);
DISPLAY INVISIBLE (-2950 5800);
FORCEPROP 1 LASTPIN (-3000 5775) $PN 1
J 0
(-2990 5755);
DISPLAY 0.489362 (-2990 5755);
PAINT MONO (-2990 5755);
FORCEPROP 1 LASTPIN (-3000 5575) $PN 2
J 0
(-2990 5555);
DISPLAY 0.489362 (-2990 5555);
PAINT MONO (-2990 5555);
FORCEPROP 1 LAST PACK_TYPE C0402
J 0
(-2950 5475);
DISPLAY 0.489362 (-2950 5475);
PAINT SKYBLUE (-2950 5475);
FORCEPROP 1 LAST MATERIAL X6S
J 0
(-2950 5575);
DISPLAY 0.489362 (-2950 5575);
PAINT SKYBLUE (-2950 5575);
FORCEPROP 1 LAST TOLERANCE 20%
J 0
(-2950 5625);
DISPLAY 0.489362 (-2950 5625);
PAINT SKYBLUE (-2950 5625);
FORCEPROP 1 LAST VALUE 10UF
J 0
(-2950 5725);
DISPLAY 0.489362 (-2950 5725);
PAINT SKYBLUE (-2950 5725);
FORCEPROP 1 LAST VOLTAGE 6.3V
J 0
(-2950 5675);
DISPLAY 0.489362 (-2950 5675);
PAINT SKYBLUE (-2950 5675);
FORCEPROP 2 LAST CDS_LIB pure_quanta
J 0
(-3000 5675);
DISPLAY INVISIBLE (-3000 5675);
FORCEPROP 1 LAST PATH I80
J 0
(-2950 5825);
DISPLAY 0.978723 (-2950 5825);
PAINT WHITE (-2950 5825);
DISPLAY INVISIBLE (-2950 5825);
FORCEPROP 1 LAST PART_NUMBER CH6101MEB03
J 0
(-2950 5525);
DISPLAY 0.489362 (-2950 5525);
PAINT SKYBLUE (-2950 5525);
DISPLAY INVISIBLE (-2950 5525);
FORCEADD Q_CAP..1
(-3000 6150);
FORCEPROP 1 LAST LOCATION PC645
J 0
(-2950 6250);
DISPLAY 0.489362 (-2950 6250);
PAINT SKYBLUE (-2950 6250);
FORCEPROP 0 LAST $SEC 1
J 0
(-2950 6275);
DISPLAY 0.680851 (-2950 6275);
PAINT MONO (-2950 6275);
DISPLAY INVISIBLE (-2950 6275);
FORCEPROP 0 LAST CDS_SEC 1
J 0
(-2950 6275);
DISPLAY 1.021277 (-2950 6275);
DISPLAY INVISIBLE (-2950 6275);
FORCEPROP 1 LASTPIN (-3000 6250) $PN 1
J 0
(-2990 6230);
DISPLAY 0.489362 (-2990 6230);
PAINT MONO (-2990 6230);
FORCEPROP 1 LASTPIN (-3000 6050) $PN 2
J 0
(-2990 6030);
DISPLAY 0.489362 (-2990 6030);
PAINT MONO (-2990 6030);
FORCEPROP 1 LAST PACK_TYPE C0402
J 0
(-2950 5950);
DISPLAY 0.489362 (-2950 5950);
PAINT SKYBLUE (-2950 5950);
FORCEPROP 1 LAST VOLTAGE 16V
J 0
(-2950 6150);
DISPLAY 0.489362 (-2950 6150);
PAINT SKYBLUE (-2950 6150);
FORCEPROP 1 LAST VALUE 1UF
J 0
(-2950 6200);
DISPLAY 0.489362 (-2950 6200);
PAINT SKYBLUE (-2950 6200);
FORCEPROP 1 LAST TOLERANCE 10%
J 0
(-2950 6100);
DISPLAY 0.489362 (-2950 6100);
PAINT SKYBLUE (-2950 6100);
FORCEPROP 1 LAST MATERIAL X6S
J 0
(-2950 6050);
DISPLAY 0.489362 (-2950 6050);
PAINT SKYBLUE (-2950 6050);
FORCEPROP 2 LAST CDS_LIB pure_quanta
J 0
(-3000 6150);
DISPLAY INVISIBLE (-3000 6150);
FORCEPROP 1 LAST PATH I81
J 0
(-2950 6300);
DISPLAY 0.978723 (-2950 6300);
PAINT WHITE (-2950 6300);
DISPLAY INVISIBLE (-2950 6300);
FORCEPROP 1 LAST PART_NUMBER CH5103KEB01
J 0
(-2950 6000);
DISPLAY 0.489362 (-2950 6000);
PAINT SKYBLUE (-2950 6000);
DISPLAY INVISIBLE (-2950 6000);
FORCEADD UNIVERSAL_GND..1
(-3000 5950);
FORCEPROP 3 LASTPIN (-3000 6000) SIG_NAME GND\g
J 0
(-2990 6010);
DISPLAY 0.659574 (-2990 6010);
PAINT MONO (-2990 6010);
DISPLAY INVISIBLE (-2990 6010);
FORCEPROP 2 LAST CDS_LIB pure_quanta_power
J 0
(-3000 5950);
DISPLAY INVISIBLE (-3000 5950);
FORCEPROP 1 LAST HDL_POWER GND
J 1
(-2975 5875);
DISPLAY 0.872340 (-2975 5875);
PAINT GREEN (-2975 5875);
DISPLAY INVISIBLE (-2975 5875);
FORCEPROP 1 LAST PATH I82
J 0
(-2925 5950);
DISPLAY 0.872340 (-2925 5950);
PAINT AQUA (-2925 5950);
DISPLAY INVISIBLE (-2925 5950);
FORCEADD OFFPAGE..5
R 2
(-2800 5825);
FORCEPROP 2 LAST $XR0 225 
J 0
(-2611 5825);
DISPLAY 0.638298 (-2611 5825);
PAINT MONO (-2611 5825);
FORCEPROP 2 LAST CDS_LIB standard
J 2
(-2800 5825);
DISPLAY INVISIBLE (-2800 5825);
FORCEPROP 1 LAST OFFPAGE TRUE
J 2
(-3125 5700);
DISPLAY 0.872340 (-3125 5700);
PAINT GREEN (-3125 5700);
DISPLAY INVISIBLE (-3125 5700);
FORCEPROP 1 LAST COMMENT_BODY TRUE
J 2
(-2900 5750);
DISPLAY 0.872340 (-2900 5750);
PAINT GREEN (-2900 5750);
DISPLAY INVISIBLE (-2900 5750);
FORCEPROP 2 LAST PATH I83
J 0
(-2600 5875);
DISPLAY 0.680851 (-2600 5875);
DISPLAY INVISIBLE (-2600 5875);
FORCEADD Q_RES..1
(-2575 6300);
FORCEPROP 1 LAST LOCATION PR393
J 0
(-2625 6350);
DISPLAY 0.489362 (-2625 6350);
PAINT SKYBLUE (-2625 6350);
FORCEPROP 0 LAST $SEC 1
J 0
(-2625 6400);
DISPLAY 0.680851 (-2625 6400);
PAINT MONO (-2625 6400);
DISPLAY INVISIBLE (-2625 6400);
FORCEPROP 0 LAST CDS_SEC 1
J 0
(-2625 6400);
DISPLAY 1.021277 (-2625 6400);
DISPLAY INVISIBLE (-2625 6400);
FORCEPROP 1 LASTPIN (-2675 6300) $PN 1
J 0
(-2663 6312);
DISPLAY 0.489362 (-2663 6312);
PAINT MONO (-2663 6312);
FORCEPROP 1 LASTPIN (-2475 6300) $PN 2
J 0
(-2513 6312);
DISPLAY 0.489362 (-2513 6312);
PAINT MONO (-2513 6312);
FORCEPROP 1 LAST MATERIAL CHIP
J 0
(-2450 6250);
DISPLAY 0.489362 (-2450 6250);
PAINT SKYBLUE (-2450 6250);
FORCEPROP 1 LAST WATTAGE 1/16W
J 0
(-2450 6225);
DISPLAY 0.489362 (-2450 6225);
PAINT SKYBLUE (-2450 6225);
FORCEPROP 1 LAST TOLERANCE 1%
J 0
(-2450 6325);
DISPLAY 0.489362 (-2450 6325);
PAINT SKYBLUE (-2450 6325);
FORCEPROP 1 LAST VALUE 1
J 2
(-2725 6325);
DISPLAY 0.489362 (-2725 6325);
PAINT SKYBLUE (-2725 6325);
FORCEPROP 1 LAST PACK_TYPE 0402LF
J 0
(-2750 6225);
DISPLAY 0.489362 (-2750 6225);
PAINT SKYBLUE (-2750 6225);
FORCEPROP 2 LAST CDS_LIB pure_quanta
J 0
(-2575 6300);
DISPLAY INVISIBLE (-2575 6300);
FORCEPROP 1 LAST PATH I84
J 0
(-2625 6450);
DISPLAY 0.978723 (-2625 6450);
PAINT WHITE (-2625 6450);
DISPLAY INVISIBLE (-2625 6450);
FORCEPROP 1 LAST PART_NUMBER CS-1002FB04
J 0
(-2750 6250);
DISPLAY 0.489362 (-2750 6250);
PAINT SKYBLUE (-2750 6250);
DISPLAY INVISIBLE (-2750 6250);
FORCEADD VCC_CORE..1
(-2200 6400);
FORCEPROP 3 LASTPIN (-2200 6350) SIG_NAME P3V3_AUX\g
J 0
(-2190 6360);
DISPLAY 0.659574 (-2190 6360);
PAINT MONO (-2190 6360);
DISPLAY INVISIBLE (-2190 6360);
FORCEPROP 1 LAST HDL_POWER P3V3_AUX
J 1
(-2200 6450);
DISPLAY 0.489362 (-2200 6450);
PAINT GREEN (-2200 6450);
FORCEPROP 2 LAST CDS_LIB pure_quanta_power
J 0
(-2200 6400);
DISPLAY INVISIBLE (-2200 6400);
FORCEPROP 1 LAST PATH I85
J 0
(-2150 6425);
DISPLAY 0.872340 (-2150 6425);
PAINT AQUA (-2150 6425);
DISPLAY INVISIBLE (-2150 6425);
FORCEADD RAA229621GNPHA0..1
(-4400 3375);
FORCEPROP 1 LAST LOCATION PU54
J 0
(-4950 6400);
DISPLAY 0.489362 (-4950 6400);
PAINT SKYBLUE (-4950 6400);
FORCEPROP 0 LAST $SEC 1
J 0
(-4925 6575);
DISPLAY 0.680851 (-4925 6575);
PAINT MONO (-4925 6575);
DISPLAY INVISIBLE (-4925 6575);
FORCEPROP 0 LAST CDS_SEC 1
J 0
(-4925 6575);
DISPLAY 1.021277 (-4925 6575);
DISPLAY INVISIBLE (-4925 6575);
FORCEPROP 0 LASTPIN (-3750 1875) $PN 30
J 0
(-3740 1885);
DISPLAY 0.489362 (-3740 1885);
PAINT MONO (-3740 1885);
FORCEPROP 0 LASTPIN (-3750 2325) $PN 29
J 0
(-3740 2335);
DISPLAY 0.489362 (-3740 2335);
PAINT MONO (-3740 2335);
FORCEPROP 0 LASTPIN (-3750 2775) $PN 28
J 0
(-3740 2785);
DISPLAY 0.489362 (-3740 2785);
PAINT MONO (-3740 2785);
FORCEPROP 0 LASTPIN (-3750 3225) $PN 27
J 0
(-3740 3235);
DISPLAY 0.489362 (-3740 3235);
PAINT MONO (-3740 3235);
FORCEPROP 0 LASTPIN (-3750 3675) $PN 26
J 0
(-3740 3685);
DISPLAY 0.489362 (-3740 3685);
PAINT MONO (-3740 3685);
FORCEPROP 0 LASTPIN (-3750 4125) $PN 25
J 0
(-3740 4135);
DISPLAY 0.489362 (-3740 4135);
PAINT MONO (-3740 4135);
FORCEPROP 0 LASTPIN (-3750 4575) $PN 24
J 0
(-3740 4585);
DISPLAY 0.489362 (-3740 4585);
PAINT MONO (-3740 4585);
FORCEPROP 0 LASTPIN (-3750 5025) $PN 23
J 0
(-3740 5035);
DISPLAY 0.489362 (-3740 5035);
PAINT MONO (-3740 5035);
FORCEPROP 0 LASTPIN (-5100 5975) $PN 13
J 2
(-5110 5985);
DISPLAY 0.489362 (-5110 5985);
PAINT MONO (-5110 5985);
FORCEPROP 0 LASTPIN (-5100 1425) $PN 34
J 2
(-5110 1435);
DISPLAY 0.489362 (-5110 1435);
PAINT MONO (-5110 1435);
FORCEPROP 0 LASTPIN (-5100 4675) $PN 11
J 2
(-5110 4685);
DISPLAY 0.489362 (-5110 4685);
PAINT MONO (-5110 4685);
FORCEPROP 0 LASTPIN (-5100 2125) $PN 33
J 2
(-5110 2135);
DISPLAY 0.489362 (-5110 2135);
PAINT MONO (-5110 2135);
FORCEPROP 0 LASTPIN (-5100 6125) $PN 12
J 2
(-5110 6135);
DISPLAY 0.489362 (-5110 6135);
PAINT MONO (-5110 6135);
FORCEPROP 0 LASTPIN (-5100 875) $PN 16
J 2
(-5110 885);
DISPLAY 0.489362 (-5110 885);
PAINT MONO (-5110 885);
FORCEPROP 0 LASTPIN (-5100 4975) $PN 10
J 2
(-5110 4985);
DISPLAY 0.489362 (-5110 4985);
PAINT MONO (-5110 4985);
FORCEPROP 0 LASTPIN (-5100 4825) $PN 9
J 2
(-5110 4835);
DISPLAY 0.489362 (-5110 4835);
PAINT MONO (-5110 4835);
FORCEPROP 0 LASTPIN (-3750 1975) $PN 1
J 0
(-3740 1985);
DISPLAY 0.489362 (-3740 1985);
PAINT MONO (-3740 1985);
FORCEPROP 0 LASTPIN (-3750 2425) $PN 2
J 0
(-3740 2435);
DISPLAY 0.489362 (-3740 2435);
PAINT MONO (-3740 2435);
FORCEPROP 0 LASTPIN (-3750 2875) $PN 3
J 0
(-3740 2885);
DISPLAY 0.489362 (-3740 2885);
PAINT MONO (-3740 2885);
FORCEPROP 0 LASTPIN (-3750 3325) $PN 4
J 0
(-3740 3335);
DISPLAY 0.489362 (-3740 3335);
PAINT MONO (-3740 3335);
FORCEPROP 0 LASTPIN (-3750 3775) $PN 5
J 0
(-3740 3785);
DISPLAY 0.489362 (-3740 3785);
PAINT MONO (-3740 3785);
FORCEPROP 0 LASTPIN (-3750 4225) $PN 6
J 0
(-3740 4235);
DISPLAY 0.489362 (-3740 4235);
PAINT MONO (-3740 4235);
FORCEPROP 0 LASTPIN (-3750 4675) $PN 7
J 0
(-3740 4685);
DISPLAY 0.489362 (-3740 4685);
PAINT MONO (-3740 4685);
FORCEPROP 0 LASTPIN (-3750 5125) $PN 8
J 0
(-3740 5135);
DISPLAY 0.489362 (-3740 5135);
PAINT MONO (-3740 5135);
FORCEPROP 0 LASTPIN (-3750 1625) $PN 14
J 0
(-3740 1635);
DISPLAY 0.489362 (-3740 1635);
PAINT MONO (-3740 1635);
FORCEPROP 0 LASTPIN (-5100 3825) $PN 22
J 2
(-5110 3835);
DISPLAY 0.489362 (-5110 3835);
PAINT MONO (-5110 3835);
FORCEPROP 0 LASTPIN (-5100 2725) $PN 31
J 2
(-5110 2735);
DISPLAY 0.489362 (-5110 2735);
PAINT MONO (-5110 2735);
FORCEPROP 0 LASTPIN (-5100 5675) $PN 18
J 2
(-5110 5685);
DISPLAY 0.489362 (-5110 5685);
PAINT MONO (-5110 5685);
FORCEPROP 0 LASTPIN (-5100 5525) $PN 17
J 2
(-5110 5535);
DISPLAY 0.489362 (-5110 5535);
PAINT MONO (-5110 5535);
FORCEPROP 0 LASTPIN (-5100 5225) $PN 20
J 2
(-5110 5235);
DISPLAY 0.489362 (-5110 5235);
PAINT MONO (-5110 5235);
FORCEPROP 0 LASTPIN (-5100 5375) $PN 19
J 2
(-5110 5385);
DISPLAY 0.489362 (-5110 5385);
PAINT MONO (-5110 5385);
FORCEPROP 0 LASTPIN (-3750 925) $PN 36
J 0
(-3740 935);
DISPLAY 0.489362 (-3740 935);
PAINT MONO (-3740 935);
FORCEPROP 0 LASTPIN (-3750 1225) $PN 35
J 0
(-3740 1235);
DISPLAY 0.489362 (-3740 1235);
PAINT MONO (-3740 1235);
FORCEPROP 0 LASTPIN (-5100 575) $PN TH
J 2
(-5110 585);
DISPLAY 0.489362 (-5110 585);
PAINT MONO (-5110 585);
FORCEPROP 0 LASTPIN (-3750 6125) $PN 39
J 0
(-3740 6135);
DISPLAY 0.489362 (-3740 6135);
PAINT MONO (-3740 6135);
FORCEPROP 0 LASTPIN (-3750 5825) $PN 40
J 0
(-3740 5835);
DISPLAY 0.489362 (-3740 5835);
PAINT MONO (-3740 5835);
FORCEPROP 0 LASTPIN (-5100 1875) $PN 15
J 2
(-5110 1885);
DISPLAY 0.489362 (-5110 1885);
PAINT MONO (-5110 1885);
FORCEPROP 0 LASTPIN (-5100 675) $PN 38
J 2
(-5110 685);
DISPLAY 0.489362 (-5110 685);
PAINT MONO (-5110 685);
FORCEPROP 0 LASTPIN (-5100 775) $PN 37
J 2
(-5110 785);
DISPLAY 0.489362 (-5110 785);
PAINT MONO (-5110 785);
FORCEPROP 0 LASTPIN (-5100 4075) $PN 21
J 2
(-5110 4085);
DISPLAY 0.489362 (-5110 4085);
PAINT MONO (-5110 4085);
FORCEPROP 0 LASTPIN (-5100 2975) $PN 32
J 2
(-5110 2985);
DISPLAY 0.489362 (-5110 2985);
PAINT MONO (-5110 2985);
FORCEPROP 2 LAST VALUE RAA229621GNP#HA0
J 0
(-4950 6475);
DISPLAY 0.489362 (-4950 6475);
PAINT SKYBLUE (-4950 6475);
FORCEPROP 1 LAST MATERIAL IC
J 0
(-4950 6250);
DISPLAY 0.489362 (-4950 6250);
PAINT SKYBLUE (-4950 6250);
FORCEPROP 2 LAST PART_TYPE SMLF
J 0
(-4950 6525);
DISPLAY 1.021277 (-4950 6525);
FORCEPROP 1 LAST CDS_LMAN_SYM_OUTLINE -550,2850,500,-2850
J 0
(-4400 3375);
DISPLAY 0.468085 (-4400 3375);
PAINT GREEN (-4400 3375);
DISPLAY INVISIBLE (-4400 3375);
FORCEPROP 2 LAST CDS_LIB pure_quanta
J 0
(-4400 3375);
DISPLAY INVISIBLE (-4400 3375);
FORCEPROP 1 LAST NEEDS_NO_SIZE TRUE
J 0
(-4400 3375);
DISPLAY 0.723404 (-4400 3375);
PAINT GREEN (-4400 3375);
DISPLAY INVISIBLE (-4400 3375);
FORCEPROP 1 LAST PATH I86
J 0
(-4400 3375);
DISPLAY 0.723404 (-4400 3375);
PAINT GREEN (-4400 3375);
DISPLAY INVISIBLE (-4400 3375);
FORCEPROP 1 LAST PART_NUMBER ARF0TGP4003
J 0
(-4950 6325);
DISPLAY 0.489362 (-4950 6325);
PAINT SKYBLUE (-4950 6325);
DISPLAY INVISIBLE (-4950 6325);
FORCEADD UNIVERSAL_GND..1
(-6375 4300);
FORCEPROP 3 LASTPIN (-6375 4350) SIG_NAME GND\g
J 0
(-6365 4360);
DISPLAY 0.659574 (-6365 4360);
PAINT MONO (-6365 4360);
DISPLAY INVISIBLE (-6365 4360);
FORCEPROP 2 LAST CDS_LIB pure_quanta_power
J 0
(-6375 4300);
PAINT MONO (-6375 4300);
DISPLAY INVISIBLE (-6375 4300);
FORCEPROP 1 LAST HDL_POWER GND
J 1
(-6350 4225);
DISPLAY 0.872340 (-6350 4225);
PAINT GREEN (-6350 4225);
DISPLAY INVISIBLE (-6350 4225);
FORCEPROP 1 LAST PATH I87
J 0
(-6300 4300);
DISPLAY 0.872340 (-6300 4300);
PAINT AQUA (-6300 4300);
DISPLAY INVISIBLE (-6300 4300);
FORCEADD Q_CAP..1
(-6375 4500);
FORCEPROP 1 LAST LOCATION C5010
J 0
(-6275 4500);
DISPLAY 0.510638 (-6275 4500);
FORCEPROP 0 LAST $SEC 1
J 0
(-6125 4525);
DISPLAY 0.680851 (-6125 4525);
PAINT MONO (-6125 4525);
DISPLAY INVISIBLE (-6125 4525);
FORCEPROP 0 LAST CDS_SEC 1
J 0
(-6125 4525);
DISPLAY 0.680851 (-6125 4525);
DISPLAY INVISIBLE (-6125 4525);
FORCEPROP 1 LASTPIN (-6375 4600) $PN 1
J 0
(-6365 4580);
DISPLAY 0.787234 (-6365 4580);
PAINT MONO (-6365 4580);
FORCEPROP 1 LASTPIN (-6375 4400) $PN 2
J 0
(-6365 4380);
DISPLAY 0.787234 (-6365 4380);
PAINT MONO (-6365 4380);
FORCEPROP 1 LAST VOLTAGE 50V
J 0
(-6125 4425);
DISPLAY 0.510638 (-6125 4425);
FORCEPROP 1 LAST TOLERANCE 5%
J 0
(-6125 4400);
DISPLAY 0.510638 (-6125 4400);
FORCEPROP 1 LAST VALUE 1000PF
J 0
(-6300 4475);
DISPLAY 0.510638 (-6300 4475);
FORCEPROP 1 LAST MATERIAL X7R
J 0
(-6125 4450);
DISPLAY 0.510638 (-6125 4450);
FORCEPROP 1 LAST PACK_TYPE 0402
J 0
(-6125 4475);
DISPLAY 0.510638 (-6125 4475);
FORCEPROP 2 LAST CDS_LIB pure_quanta
J 0
(-6375 4500);
DISPLAY INVISIBLE (-6375 4500);
FORCEPROP 1 LAST PATH I88
J 0
(-6325 4650);
DISPLAY 0.978723 (-6325 4650);
PAINT WHITE (-6325 4650);
DISPLAY INVISIBLE (-6325 4650);
FORCEPROP 1 LAST PART_NUMBER TMP_QCH21006JB10
J 0
(-6125 4500);
DISPLAY 0.510638 (-6125 4500);
DISPLAY INVISIBLE (-6125 4500);
FORCEADD Q_RES..1
(-5900 1425);
FORCEPROP 1 LAST LOCATION PR464
J 0
(-5950 1450);
DISPLAY 0.638298 (-5950 1450);
FORCEPROP 0 LAST $SEC 1
J 0
(-5775 1500);
DISPLAY 0.680851 (-5775 1500);
PAINT MONO (-5775 1500);
DISPLAY INVISIBLE (-5775 1500);
FORCEPROP 0 LAST CDS_SEC 1
J 0
(-5775 1500);
DISPLAY 0.680851 (-5775 1500);
DISPLAY INVISIBLE (-5775 1500);
FORCEPROP 1 LASTPIN (-6000 1425) $PN 1
J 0
(-5988 1437);
DISPLAY 0.787234 (-5988 1437);
PAINT MONO (-5988 1437);
FORCEPROP 1 LASTPIN (-5800 1425) $PN 2
J 0
(-5838 1437);
DISPLAY 0.787234 (-5838 1437);
PAINT MONO (-5838 1437);
FORCEPROP 1 LAST VALUE 13.7K
J 2
(-6000 1450);
DISPLAY 0.638298 (-6000 1450);
FORCEPROP 1 LAST WATTAGE 1/16W
J 2
(-5625 1375);
DISPLAY 0.638298 (-5625 1375);
FORCEPROP 1 LAST TOLERANCE 1%
J 0
(-5775 1450);
DISPLAY 0.638298 (-5775 1450);
FORCEPROP 1 LAST MATERIAL CHIP
J 0
(-6150 1325);
DISPLAY 0.638298 (-6150 1325);
FORCEPROP 1 LAST PACK_TYPE 0402LF
J 0
(-5775 1325);
DISPLAY 0.638298 (-5775 1325);
FORCEPROP 2 LAST CDS_LIB pure_quanta
J 0
(-5900 1425);
DISPLAY INVISIBLE (-5900 1425);
FORCEPROP 1 LAST PATH I89
J 0
(-5950 1575);
DISPLAY 0.978723 (-5950 1575);
PAINT WHITE (-5950 1575);
DISPLAY INVISIBLE (-5950 1575);
FORCEPROP 1 LAST PART_NUMBER CS31372FB03
J 0
(-6150 1375);
DISPLAY 0.638298 (-6150 1375);
DISPLAY INVISIBLE (-6150 1375);
FORCEADD Q_RES..1
(-6175 1725);
FORCEPROP 1 LAST LOCATION R8146
J 0
(-6225 1775);
DISPLAY 0.489362 (-6225 1775);
PAINT SKYBLUE (-6225 1775);
FORCEPROP 0 LAST $SEC 1
J 0
(-6225 1800);
DISPLAY 0.680851 (-6225 1800);
PAINT MONO (-6225 1800);
DISPLAY INVISIBLE (-6225 1800);
FORCEPROP 0 LAST CDS_SEC 1
J 0
(-6225 1800);
DISPLAY 1.021277 (-6225 1800);
DISPLAY INVISIBLE (-6225 1800);
FORCEPROP 1 LASTPIN (-6275 1725) $PN 1
J 0
(-6263 1737);
DISPLAY 0.489362 (-6263 1737);
PAINT MONO (-6263 1737);
FORCEPROP 1 LASTPIN (-6075 1725) $PN 2
J 0
(-6113 1737);
DISPLAY 0.489362 (-6113 1737);
PAINT MONO (-6113 1737);
FORCEPROP 1 LAST TOLERANCE 5%
J 0
(-6050 1750);
DISPLAY 0.489362 (-6050 1750);
PAINT SKYBLUE (-6050 1750);
FORCEPROP 1 LAST WATTAGE 1/16W
J 0
(-6075 1675);
DISPLAY 0.489362 (-6075 1675);
PAINT SKYBLUE (-6075 1675);
FORCEPROP 1 LAST MATERIAL EMPTY
J 0
(-6425 1650);
DISPLAY 0.489362 (-6425 1650);
PAINT RED (-6425 1650);
FORCEPROP 1 LAST PACK_TYPE 0402LF
J 0
(-6075 1650);
DISPLAY 0.489362 (-6075 1650);
PAINT SKYBLUE (-6075 1650);
FORCEPROP 1 LAST VALUE 0
J 2
(-6300 1750);
DISPLAY 0.489362 (-6300 1750);
PAINT SKYBLUE (-6300 1750);
FORCEPROP 2 LAST CDS_LIB pure_quanta
J 0
(-6175 1725);
DISPLAY INVISIBLE (-6175 1725);
FORCEPROP 1 LAST PATH I9
J 0
(-6225 1875);
DISPLAY 0.978723 (-6225 1875);
PAINT WHITE (-6225 1875);
DISPLAY INVISIBLE (-6225 1875);
FORCEPROP 1 LAST PART_NUMBER CS00002JB13
J 0
(-6425 1675);
DISPLAY 0.489362 (-6425 1675);
PAINT SKYBLUE (-6425 1675);
DISPLAY INVISIBLE (-6425 1675);
FORCEADD DNS..1
(-5700 475);
PAINT RED (-5700 475);
FORCEPROP 2 LAST CDS_LIB mstr_misc
J 0
(-5700 475);
DISPLAY INVISIBLE (-5700 475);
FORCEPROP 1 LAST COMMENT_BODY TRUE
R 1
J 0
(-5625 250);
DISPLAY 0.872340 (-5625 250);
PAINT GREEN (-5625 250);
DISPLAY INVISIBLE (-5625 250);
FORCEADD DNS..1
(-2125 1400);
PAINT RED (-2125 1400);
FORCEPROP 2 LAST CDS_LIB mstr_misc
J 0
(-2125 1400);
DISPLAY INVISIBLE (-2125 1400);
FORCEPROP 1 LAST COMMENT_BODY TRUE
R 1
J 0
(-2050 1175);
DISPLAY 0.872340 (-2050 1175);
PAINT GREEN (-2050 1175);
DISPLAY INVISIBLE (-2050 1175);
FORCEADD DNS..1
(-1650 1600);
PAINT RED (-1650 1600);
FORCEPROP 2 LAST CDS_LIB mstr_misc
J 0
(-1650 1600);
DISPLAY INVISIBLE (-1650 1600);
FORCEPROP 1 LAST COMMENT_BODY TRUE
R 1
J 0
(-1575 1375);
DISPLAY 0.872340 (-1575 1375);
PAINT GREEN (-1575 1375);
DISPLAY INVISIBLE (-1575 1375);
FORCEADD DNS..1
(-1700 1825);
PAINT RED (-1700 1825);
FORCEPROP 2 LAST CDS_LIB mstr_misc
J 0
(-1700 1825);
DISPLAY INVISIBLE (-1700 1825);
FORCEPROP 1 LAST COMMENT_BODY TRUE
R 1
J 0
(-1625 1600);
DISPLAY 0.872340 (-1625 1600);
PAINT GREEN (-1625 1600);
DISPLAY INVISIBLE (-1625 1600);
FORCEADD DNS..1
(-5975 2325);
PAINT RED (-5975 2325);
FORCEPROP 2 LAST CDS_LIB mstr_misc
J 0
(-5975 2325);
DISPLAY INVISIBLE (-5975 2325);
FORCEPROP 1 LAST COMMENT_BODY TRUE
R 1
J 0
(-5900 2100);
DISPLAY 0.872340 (-5900 2100);
PAINT GREEN (-5900 2100);
DISPLAY INVISIBLE (-5900 2100);
FORCEADD DNS..1
(-5325 6375);
PAINT RED (-5325 6375);
FORCEPROP 2 LAST CDS_LIB mstr_misc
J 0
(-5325 6375);
DISPLAY INVISIBLE (-5325 6375);
FORCEPROP 1 LAST COMMENT_BODY TRUE
R 1
J 0
(-5250 6150);
DISPLAY 0.872340 (-5250 6150);
PAINT GREEN (-5250 6150);
DISPLAY INVISIBLE (-5250 6150);
FORCEADD DNS..1
(-6250 1725);
PAINT RED (-6250 1725);
FORCEPROP 2 LAST CDS_LIB mstr_misc
J 0
(-6250 1725);
DISPLAY INVISIBLE (-6250 1725);
FORCEPROP 1 LAST COMMENT_BODY TRUE
R 1
J 0
(-6175 1500);
DISPLAY 0.872340 (-6175 1500);
PAINT GREEN (-6175 1500);
DISPLAY INVISIBLE (-6175 1500);
FORCEADD DNS..1
(-6250 2100);
PAINT RED (-6250 2100);
FORCEPROP 2 LAST CDS_LIB mstr_misc
J 0
(-6250 2100);
DISPLAY INVISIBLE (-6250 2100);
FORCEPROP 1 LAST COMMENT_BODY TRUE
R 1
J 0
(-6175 1875);
DISPLAY 0.872340 (-6175 1875);
PAINT GREEN (-6175 1875);
DISPLAY INVISIBLE (-6175 1875);
FORCEADD QUANTA_TITLE_BLOCK_C..1
(0 0);
FORCEPROP 0 LAST CDS_CON_LAST_MODIFIED Thu Sep 14 16:12:42 2023
J 0
(-1885 15);
DISPLAY INVISIBLE (-1885 15);
FORCEPROP 1 LAST CUSTOM_TXT_CDS <CON_LAST_MODIFIED>
J 0
(-1885 15);
DISPLAY 0.978723 (-1885 15);
FORCEPROP 2 LAST CUSTOM_TXT_CDS <XR_PAGE_TITLE>
J 0
(-7890 5250);
DISPLAY 0.638298 (-7890 5250);
PAINT PINK (-7890 5250);
DISPLAY INVISIBLE (-7890 5250);
FORCEPROP 1 LAST CUSTOM_TXT_CDS <NAME_2>
J 0
(-3175 50);
FORCEPROP 1 LAST CUSTOM_TXT_CDS <NAME_1>
J 0
(-3175 175);
FORCEPROP 1 LAST CUSTOM_TXT_CDS <Q_NUMBER>
J 0
(-1403 103);
DISPLAY 1.212766 (-1403 103);
FORCEPROP 1 LAST CUSTOM_TXT_CDS <Q_PROJ>
J 0
(-2382 102);
DISPLAY 1.212766 (-2382 102);
FORCEPROP 1 LAST CUSTOM_TXT_CDS <Q_REV>
J 0
(-184 103);
DISPLAY 1.212766 (-184 103);
FORCEPROP 1 LAST CUSTOM_TXT_CDS <CON_PAGE_NUM> OF <CON_TOTAL_PAGES>
J 0
(-446 18);
DISPLAY 0.978723 (-446 18);
FORCEPROP 1 LAST Q_TITLE PVDD11_S3_P1 VR CONTROLLER
J 0
(-9325 25);
DISPLAY 2.446809 (-9325 25);
PAINT GREEN (-9325 25);
FORCEPROP 2 LAST PAGE_BORDER TRUE
J 0
(-7890 5250);
DISPLAY 0.638298 (-7890 5250);
PAINT PINK (-7890 5250);
DISPLAY INVISIBLE (-7890 5250);
FORCEPROP 2 LAST CDS_LIB pure_quanta
J 0
(0 0);
DISPLAY INVISIBLE (0 0);
FORCEPROP 1 LAST CDS_LMAN_SYM_OUTLINE -9475,6775,100,-125
J 0
(0 0);
DISPLAY 0.468085 (0 0);
PAINT GREEN (0 0);
DISPLAY INVISIBLE (0 0);
FORCEPROP 2 LAST CDS_XR_PAGE_TITLE CR-224 : @T6G_MB_LIB.T6G(SCH_1):PAGE224
J 0
(-7890 5250);
DISPLAY 0.638298 (-7890 5250);
PAINT PINK (-7890 5250);
DISPLAY INVISIBLE (-7890 5250);
FORCEPROP 1 LAST Q_DEPT BU9
J 1
(-3763 49);
DISPLAY 1.957447 (-3763 49);
PAINT GREEN (-3763 49);
DISPLAY INVISIBLE (-3763 49);
FORCEPROP 1 LAST COMMENT_BODY TRUE
J 0
(12 -13);
DISPLAY 0.978723 (12 -13);
PAINT GREEN (12 -13);
DISPLAY INVISIBLE (12 -13);
WIRE 16 -1 (-6750 3575)(-6750 3550);
WIRE 16 -1 (-5725 375)(-5725 325);
WIRE 16 -1 (-5400 400)(-5400 325);
WIRE 16 -1 (-6000 1425)(-6175 1425);
WIRE 16 -1 (-6175 1425)(-6175 1200);
WIRE 16 -1 (-5975 2450)(-5975 2500);
WIRE 16 -1 (-6950 575)(-6950 475);
WIRE 16 -1 (-6750 4350)(-6750 4400);
WIRE 16 -1 (-3450 625)(-3450 500);
WIRE 16 -1 (-6525 575)(-6525 450);
WIRE 16 -1 (-3025 1225)(-2675 1225);
WIRE 16 -1 (-2675 1225)(-2675 1200);
WIRE 16 -1 (-3025 1875)(-2675 1875);
WIRE 16 -1 (-2675 1875)(-2675 1850);
WIRE 16 -1 (-2125 1325)(-2125 1250);
WIRE 16 -1 (-3025 2325)(-2675 2325);
WIRE 16 -1 (-2675 2325)(-2675 2300);
WIRE 16 -1 (-3025 2775)(-2675 2775);
WIRE 16 -1 (-2675 2775)(-2675 2750);
WIRE 16 -1 (-3025 3225)(-2675 3225);
WIRE 16 -1 (-2675 3225)(-2675 3200);
WIRE 16 -1 (-3025 3675)(-2675 3675);
WIRE 16 -1 (-2675 3675)(-2675 3650);
WIRE 16 -1 (-3025 4125)(-2675 4125);
WIRE 16 -1 (-2675 4125)(-2675 4100);
WIRE 16 -1 (-3375 5575)(-3375 5500);
WIRE 16 -1 (-3375 6050)(-3375 5950);
WIRE 16 -1 (-3000 5500)(-3000 5575);
WIRE 16 -1 (-3000 6000)(-3000 6050);
WIRE 16 -1 (-6375 4400)(-6375 4350);
WIRE 16 -1 (-7500 3825)(-6750 3825);
FORCEPROP 2 LAST SIG_NAME VSENSE_VSS_SENSE_C_P1
J 2
(-6910 3835);
DISPLAY 0.489362 (-6910 3835);
WIRE 16 -1 (-6750 3825)(-5750 3825);
WIRE 16 -1 (-6750 3775)(-6750 3825);
WIRE 16 -1 (-5750 3825)(-5100 3825);
WIRE 16 -1 (-5750 3850)(-5750 3825);
WIRE 17 273 (-7800 4225)(-7475 4225);
WIRE 17 273 (-7800 3675)(-7800 4225);
WIRE 17 273 (-7475 4225)(-7475 3675);
WIRE 17 273 (-7800 3675)(-7475 3675);
WIRE 16 -1 (-6150 4075)(-6750 4075);
WIRE 16 -1 (-6750 4150)(-6750 4075);
WIRE 16 -1 (-6750 4075)(-7500 4075);
FORCEPROP 2 LAST SIG_NAME VSENSE_PVDD11_S3_P1_DP
J 2
(-6910 4085);
DISPLAY 0.489362 (-6910 4085);
WIRE 16 -1 (-6775 4825)(-6150 4825);
FORCEPROP 2 LAST SIG_NAME SMB_SCM_2_R2_SDA
J 0
(-6750 4835);
DISPLAY 0.489362 (-6750 4835);
WIRE 16 -1 (-6775 4975)(-6150 4975);
FORCEPROP 2 LAST SIG_NAME SMB_SCM_2_R2_SCL
J 0
(-6750 4985);
DISPLAY 0.489362 (-6750 4985);
WIRE 16 -1 (-5950 4675)(-5100 4675);
FORCEPROP 2 LAST SIG_NAME PVDD11_S3_P1_PMALERT_R
J 2
(-5185 4685);
DISPLAY 0.489362 (-5185 4685);
FORCEPROP 2 LASTPROP $XRERR UNIQUE?
J 0
(-5425 4685);
DISPLAY 0.638298 (-5425 4685);
PAINT MONO (-5425 4685);
DISPLAY INVISIBLE (-5425 4685);
WIRE 16 -1 (-5100 4825)(-5950 4825);
FORCEPROP 2 LAST SIG_NAME PVDD11_S3_P1_PMSDA_R
J 2
(-5235 4835);
DISPLAY 0.489362 (-5235 4835);
FORCEPROP 2 LASTPROP $XRERR UNIQUE?
J 0
(-5475 4835);
DISPLAY 0.638298 (-5475 4835);
PAINT MONO (-5475 4835);
DISPLAY INVISIBLE (-5475 4835);
WIRE 16 -1 (-5100 4975)(-5950 4975);
FORCEPROP 2 LAST SIG_NAME PVDD11_S3_P1_PMSCL_R
J 2
(-5235 4985);
DISPLAY 0.489362 (-5235 4985);
FORCEPROP 2 LASTPROP $XRERR UNIQUE?
J 0
(-5475 4985);
DISPLAY 0.638298 (-5475 4985);
PAINT MONO (-5475 4985);
DISPLAY INVISIBLE (-5475 4985);
WIRE 16 -1 (-6050 5225)(-5100 5225);
WIRE 16 -1 (-6050 5525)(-6050 5225);
WIRE 16 -1 (-6050 5175)(-6050 5225);
WIRE 16 -1 (-6050 5525)(-5100 5525);
WIRE 16 -1 (-6050 5675)(-6050 5525);
WIRE 16 -1 (-5100 5675)(-6050 5675);
WIRE 16 -1 (-5100 5375)(-5800 5375);
FORCEPROP 2 LAST SIG_NAME NC_PVDD11_S3_P1_SVTO
J 2
(-5285 5385);
DISPLAY 0.489362 (-5285 5385);
FORCEPROP 2 LASTPROP $XRERR UNIQUE?
J 0
(-6040 5375);
DISPLAY 0.638298 (-6040 5375);
PAINT MONO (-6040 5375);
DISPLAY INVISIBLE (-6040 5375);
WIRE 17 273 (-1750 6625)(-175 6625);
WIRE 17 273 (-1750 6625)(-1750 5725);
WIRE 17 273 (-175 6625)(-175 5725);
WIRE 17 273 (-1750 5725)(-175 5725);
WIRE 16 -1 (-5100 2975)(-5375 2975);
WIRE 16 -1 (-5375 2975)(-5375 2725);
WIRE 16 -1 (-5375 2725)(-5100 2725);
WIRE 16 -1 (-5375 2625)(-5375 2725);
WIRE 16 -1 (-3025 5025)(-3750 5025);
FORCEPROP 2 LAST SIG_NAME PVDD11_S3_P1_IMON1
J 0
(-3560 5035);
DISPLAY 0.489362 (-3560 5035);
WIRE 16 -1 (-3750 6125)(-3525 6125);
WIRE 16 -1 (-3525 6125)(-3525 6300);
WIRE 16 -1 (-3525 6300)(-3375 6300);
WIRE 16 -1 (-3375 6300)(-3000 6300);
FORCEPROP 2 LAST SIG_NAME PVDD11_S3_P1_VCC
J 2
(-3035 6325);
DISPLAY 0.489362 (-3035 6325);
FORCEPROP 2 LASTPROP $XRERR UNIQUE?
J 0
(-3275 6325);
DISPLAY 0.638298 (-3275 6325);
PAINT MONO (-3275 6325);
DISPLAY INVISIBLE (-3275 6325);
WIRE 16 -1 (-3375 6300)(-3375 6250);
WIRE 16 -1 (-2675 6300)(-3000 6300);
WIRE 16 -1 (-3000 6250)(-3000 6300);
WIRE 16 -1 (-3025 4575)(-3750 4575);
FORCEPROP 2 LAST SIG_NAME PVDD11_S3_P1_IMON2
J 0
(-3560 4585);
DISPLAY 0.489362 (-3560 4585);
WIRE 16 -1 (-3750 1625)(-2125 1625);
FORCEPROP 2 LAST SIG_NAME PVDD11_S3_P1_RESET_N_R
J 2
(-2135 1635);
DISPLAY 0.489362 (-2135 1635);
FORCEPROP 2 LASTPROP $XRERR UNIQUE?
J 0
(-2375 1635);
DISPLAY 0.638298 (-2375 1635);
PAINT MONO (-2375 1635);
DISPLAY INVISIBLE (-2375 1635);
WIRE 16 -1 (-2125 1625)(-2025 1625);
WIRE 16 -1 (-2125 1625)(-2125 1525);
WIRE 16 -1 (-2025 1625)(-1750 1625);
WIRE 16 -1 (-2025 1625)(-2025 1850);
WIRE 16 -1 (-2025 1850)(-1800 1850);
WIRE 16 -1 (-3225 4125)(-3750 4125);
FORCEPROP 2 LAST SIG_NAME NC_PVDD11_S3_P1_IMON3
J 2
(-3210 4135);
DISPLAY 0.489362 (-3210 4135);
FORCEPROP 2 LASTPROP $XRERR UNIQUE?
J 0
(-3450 4135);
DISPLAY 0.638298 (-3450 4135);
PAINT MONO (-3450 4135);
DISPLAY INVISIBLE (-3450 4135);
WIRE 16 -1 (-3225 3675)(-3750 3675);
FORCEPROP 2 LAST SIG_NAME NC_PVDD11_S3_P1_IMON4
J 2
(-3210 3685);
DISPLAY 0.489362 (-3210 3685);
FORCEPROP 2 LASTPROP $XRERR UNIQUE?
J 0
(-3450 3685);
DISPLAY 0.638298 (-3450 3685);
PAINT MONO (-3450 3685);
DISPLAY INVISIBLE (-3450 3685);
WIRE 16 -1 (-5100 875)(-5550 875);
FORCEPROP 2 LAST SIG_NAME NC_PVDD11_S3_P1_PG1
J 0
(-5595 885);
DISPLAY 0.489362 (-5595 885);
FORCEPROP 2 LASTPROP $XRERR UNIQUE?
J 0
(-5790 875);
DISPLAY 0.638298 (-5790 875);
PAINT MONO (-5790 875);
DISPLAY INVISIBLE (-5790 875);
WIRE 16 -1 (-5875 5975)(-5700 5975);
WIRE 16 -1 (-5700 5975)(-5100 5975);
FORCEPROP 2 LAST SIG_NAME PVDD11_S3_P1_EN_R
J 2
(-5210 5985);
DISPLAY 0.489362 (-5210 5985);
FORCEPROP 2 LASTPROP $XRERR UNIQUE?
J 0
(-5450 5985);
DISPLAY 0.638298 (-5450 5985);
PAINT MONO (-5450 5985);
DISPLAY INVISIBLE (-5450 5985);
WIRE 16 -1 (-5700 5850)(-5700 5975);
WIRE 16 -1 (-5400 5850)(-5700 5850);
WIRE 16 -1 (-3750 3775)(-2925 3775);
FORCEPROP 2 LAST SIG_NAME NC_PVDD11_S3_P1_PWM4
J 2
(-3185 3785);
DISPLAY 0.489362 (-3185 3785);
FORCEPROP 2 LASTPROP $XRERR UNIQUE?
J 0
(-2895 3775);
DISPLAY 0.638298 (-2895 3775);
PAINT MONO (-2895 3775);
DISPLAY INVISIBLE (-2895 3775);
WIRE 16 -1 (-3750 4225)(-2925 4225);
FORCEPROP 2 LAST SIG_NAME NC_PVDD11_S3_P1_PWM3
J 2
(-3185 4235);
DISPLAY 0.489362 (-3185 4235);
FORCEPROP 2 LASTPROP $XRERR UNIQUE?
J 0
(-2895 4225);
DISPLAY 0.638298 (-2895 4225);
PAINT MONO (-2895 4225);
DISPLAY INVISIBLE (-2895 4225);
WIRE 16 -1 (-5750 4050)(-5750 4075);
WIRE 16 -1 (-5750 4075)(-5100 4075);
FORCEPROP 2 LAST SIG_NAME VSENSE_PVDD11_S3_P1_R
J 2
(-5210 4085);
DISPLAY 0.489362 (-5210 4085);
FORCEPROP 2 LASTPROP $XRERR UNIQUE?
J 0
(-5450 4085);
DISPLAY 0.638298 (-5450 4085);
PAINT MONO (-5450 4085);
DISPLAY INVISIBLE (-5450 4085);
WIRE 16 -1 (-5950 4075)(-5750 4075);
WIRE 16 -1 (-3750 2425)(-2925 2425);
FORCEPROP 2 LAST SIG_NAME NC_PVDD11_S3_P1_PWM7
J 2
(-3185 2435);
DISPLAY 0.489362 (-3185 2435);
FORCEPROP 2 LASTPROP $XRERR UNIQUE?
J 0
(-2895 2425);
DISPLAY 0.638298 (-2895 2425);
PAINT MONO (-2895 2425);
DISPLAY INVISIBLE (-2895 2425);
WIRE 16 -1 (-5700 6400)(-5425 6400);
WIRE 16 -1 (-6100 6400)(-5700 6400);
WIRE 16 -1 (-5700 6400)(-5700 6125);
WIRE 16 -1 (-5700 6125)(-5100 6125);
FORCEPROP 2 LAST SIG_NAME PWRGD_PVDD11_S3_P1_R
J 2
(-5210 6135);
DISPLAY 0.489362 (-5210 6135);
FORCEPROP 2 LASTPROP $XRERR UNIQUE?
J 0
(-5450 6135);
DISPLAY 0.638298 (-5450 6135);
PAINT MONO (-5450 6135);
DISPLAY INVISIBLE (-5450 6135);
WIRE 16 -1 (-5700 6125)(-5875 6125);
WIRE 16 -1 (-3750 4675)(-3025 4675);
FORCEPROP 2 LAST SIG_NAME PVDD11_S3_P1_PWM2
J 0
(-3560 4685);
DISPLAY 0.489362 (-3560 4685);
WIRE 16 -1 (-3750 5825)(-3375 5825);
WIRE 16 -1 (-3375 5825)(-3000 5825);
FORCEPROP 2 LAST SIG_NAME PVDD11_S3_P1_VCCS
J 2
(-3035 5835);
DISPLAY 0.489362 (-3035 5835);
WIRE 16 -1 (-3375 5825)(-3375 5775);
WIRE 16 -1 (-2850 5825)(-3000 5825);
WIRE 16 -1 (-3000 5775)(-3000 5825);
WIRE 16 -1 (-5700 775)(-5100 775);
FORCEPROP 2 LAST SIG_NAME PVDD11_S3_P1_VMON
J 2
(-5235 785);
DISPLAY 0.489362 (-5235 785);
FORCEPROP 2 LASTPROP $XRERR UNIQUE?
J 0
(-5475 785);
DISPLAY 0.638298 (-5475 785);
PAINT MONO (-5475 785);
DISPLAY INVISIBLE (-5475 785);
WIRE 16 -1 (-5700 850)(-5700 775);
WIRE 16 -1 (-5700 850)(-6525 850);
WIRE 16 -1 (-6525 775)(-6525 850);
WIRE 16 -1 (-6950 850)(-6525 850);
WIRE 16 -1 (-6950 775)(-6950 850);
WIRE 16 -1 (-7175 850)(-6950 850);
WIRE 16 -1 (-5400 600)(-5400 675);
WIRE 16 -1 (-5100 675)(-5400 675);
FORCEPROP 2 LAST SIG_NAME PVDD11_S3_P1_VINSEN
J 2
(-5210 685);
DISPLAY 0.489362 (-5210 685);
FORCEPROP 2 LASTPROP $XRERR UNIQUE?
J 0
(-5450 685);
DISPLAY 0.638298 (-5450 685);
PAINT MONO (-5450 685);
DISPLAY INVISIBLE (-5450 685);
WIRE 16 -1 (-5725 675)(-5400 675);
WIRE 16 -1 (-5725 575)(-5725 675);
WIRE 16 -1 (-5950 675)(-5725 675);
WIRE 16 -1 (-3175 925)(-3450 925);
FORCEPROP 2 LAST SIG_NAME PVDD11_S3_P1_TEMP0
J 2
(-3235 935);
DISPLAY 0.489362 (-3235 935);
WIRE 16 -1 (-3450 825)(-3450 925);
WIRE 16 -1 (-3450 925)(-3750 925);
WIRE 16 -1 (-5100 1875)(-5825 1875);
FORCEPROP 2 LAST SIG_NAME PVDD11_S3_P1_VDDIO
J 2
(-5210 1885);
DISPLAY 0.489362 (-5210 1885);
FORCEPROP 2 LASTPROP $XRERR UNIQUE?
J 0
(-5450 1885);
DISPLAY 0.638298 (-5450 1885);
PAINT MONO (-5450 1885);
DISPLAY INVISIBLE (-5450 1885);
WIRE 16 -1 (-5825 1725)(-5825 1875);
WIRE 16 -1 (-6075 1725)(-5825 1725);
WIRE 16 -1 (-3225 2325)(-3750 2325);
FORCEPROP 2 LAST SIG_NAME NC_PVDD11_S3_P1_IMON7
J 2
(-3210 2335);
DISPLAY 0.489362 (-3210 2335);
FORCEPROP 2 LASTPROP $XRERR UNIQUE?
J 0
(-3450 2335);
DISPLAY 0.638298 (-3450 2335);
PAINT MONO (-3450 2335);
DISPLAY INVISIBLE (-3450 2335);
WIRE 16 -1 (-3750 5125)(-3025 5125);
FORCEPROP 2 LAST SIG_NAME PVDD11_S3_P1_PWM1
J 0
(-3560 5135);
DISPLAY 0.489362 (-3560 5135);
WIRE 16 -1 (-3750 3325)(-2925 3325);
FORCEPROP 2 LAST SIG_NAME NC_PVDD11_S3_P1_PWM5
J 2
(-3185 3335);
DISPLAY 0.489362 (-3185 3335);
FORCEPROP 2 LASTPROP $XRERR UNIQUE?
J 0
(-2895 3325);
DISPLAY 0.638298 (-2895 3325);
PAINT MONO (-2895 3325);
DISPLAY INVISIBLE (-2895 3325);
WIRE 16 -1 (-3225 3225)(-3750 3225);
FORCEPROP 2 LAST SIG_NAME NC_PVDD11_S3_P1_IMON5
J 2
(-3210 3235);
DISPLAY 0.489362 (-3210 3235);
FORCEPROP 2 LASTPROP $XRERR UNIQUE?
J 0
(-3450 3235);
DISPLAY 0.638298 (-3450 3235);
PAINT MONO (-3450 3235);
DISPLAY INVISIBLE (-3450 3235);
WIRE 16 -1 (-3750 2875)(-2925 2875);
FORCEPROP 2 LAST SIG_NAME NC_PVDD11_S3_P1_PWM6
J 2
(-3185 2885);
DISPLAY 0.489362 (-3185 2885);
FORCEPROP 2 LASTPROP $XRERR UNIQUE?
J 0
(-2895 2875);
DISPLAY 0.638298 (-2895 2875);
PAINT MONO (-2895 2875);
DISPLAY INVISIBLE (-2895 2875);
WIRE 16 -1 (-3225 2775)(-3750 2775);
FORCEPROP 2 LAST SIG_NAME NC_PVDD11_S3_P1_IMON6
J 2
(-3210 2785);
DISPLAY 0.489362 (-3210 2785);
FORCEPROP 2 LASTPROP $XRERR UNIQUE?
J 0
(-3450 2785);
DISPLAY 0.638298 (-3450 2785);
PAINT MONO (-3450 2785);
DISPLAY INVISIBLE (-3450 2785);
WIRE 16 -1 (-5975 2250)(-5975 2125);
WIRE 16 -1 (-5100 2125)(-5975 2125);
FORCEPROP 2 LAST SIG_NAME PVDD11_S3_P1_OCP_N_R
J 2
(-5210 2135);
DISPLAY 0.489362 (-5210 2135);
FORCEPROP 2 LASTPROP $XRERR UNIQUE?
J 0
(-5450 2135);
DISPLAY 0.638298 (-5450 2135);
PAINT MONO (-5450 2135);
DISPLAY INVISIBLE (-5450 2135);
WIRE 16 -1 (-6150 2125)(-5975 2125);
WIRE 16 -1 (-5175 575)(-5100 575);
WIRE 16 -1 (-5175 525)(-5175 575);
WIRE 16 -1 (-5800 1425)(-5100 1425);
FORCEPROP 2 LAST SIG_NAME PVDD11_S3_P1_ADDR_CFG
J 2
(-5185 1435);
DISPLAY 0.489362 (-5185 1435);
FORCEPROP 2 LASTPROP $XRERR UNIQUE?
J 0
(-5425 1435);
DISPLAY 0.638298 (-5425 1435);
PAINT MONO (-5425 1435);
DISPLAY INVISIBLE (-5425 1435);
WIRE 16 -1 (-3225 1225)(-3750 1225);
FORCEPROP 2 LAST SIG_NAME PVDD11_S3_P1_TEMP1
J 2
(-3235 1235);
DISPLAY 0.489362 (-3235 1235);
FORCEPROP 2 LASTPROP $XRERR UNIQUE?
J 0
(-3475 1235);
DISPLAY 0.638298 (-3475 1235);
PAINT MONO (-3475 1235);
DISPLAY INVISIBLE (-3475 1235);
WIRE 16 -1 (-3750 1975)(-2925 1975);
FORCEPROP 2 LAST SIG_NAME NC_PVDD11_S3_P1_PWM8
J 2
(-3185 1985);
DISPLAY 0.489362 (-3185 1985);
FORCEPROP 2 LASTPROP $XRERR UNIQUE?
J 0
(-2895 1975);
DISPLAY 0.638298 (-2895 1975);
PAINT MONO (-2895 1975);
DISPLAY INVISIBLE (-2895 1975);
WIRE 16 -1 (-3225 1875)(-3750 1875);
FORCEPROP 2 LAST SIG_NAME NC_PVDD11_S3_P1_IMON8
J 2
(-3210 1885);
DISPLAY 0.489362 (-3210 1885);
FORCEPROP 2 LASTPROP $XRERR UNIQUE?
J 0
(-3450 1885);
DISPLAY 0.638298 (-3450 1885);
PAINT MONO (-3450 1885);
DISPLAY INVISIBLE (-3450 1885);
WIRE 16 -1 (-6350 2125)(-6950 2125);
FORCEPROP 2 LAST SIG_NAME PVDD11_S3_P1_OCP_N
J 2
(-6485 2135);
DISPLAY 0.489362 (-6485 2135);
WIRE 16 -1 (-6075 5975)(-6750 5975);
FORCEPROP 2 LAST SIG_NAME PVDD11_S3_P1_EN
J 2
(-6335 5985);
DISPLAY 0.489362 (-6335 5985);
WIRE 16 -1 (-6075 6125)(-6750 6125);
FORCEPROP 2 LAST SIG_NAME PWRGD_PVDD11_S3_P1
J 2
(-6260 6135);
DISPLAY 0.489362 (-6260 6135);
WIRE 16 -1 (-800 1625)(-1550 1625);
FORCEPROP 2 LAST SIG_NAME PVDD11_S3_P1_RESET_N
J 2
(-810 1635);
DISPLAY 0.489362 (-810 1635);
WIRE 16 -1 (-6150 4675)(-6375 4675);
WIRE 16 -1 (-6375 4675)(-6375 4600);
WIRE 16 -1 (-6375 4675)(-6775 4675);
FORCEPROP 2 LAST SIG_NAME PVDD11_S3_P1_PMALERT
J 0
(-6750 4685);
DISPLAY 0.489362 (-6750 4685);
WIRE 16 -1 (-6600 6400)(-6300 6400);
WIRE 16 -1 (-6600 6475)(-6600 6400);
WIRE 16 -1 (-5075 5825)(-5075 5850);
WIRE 16 -1 (-5075 5850)(-5200 5850);
WIRE 16 -1 (-5075 6375)(-5075 6400);
WIRE 16 -1 (-5075 6400)(-5225 6400);
WIRE 16 -1 (-1350 1950)(-1350 1850);
WIRE 16 -1 (-1350 1850)(-1600 1850);
WIRE 16 -1 (-6150 675)(-6275 675);
WIRE 16 -1 (-6275 700)(-6275 675);
WIRE 16 -1 (-6600 1725)(-6275 1725);
WIRE 16 -1 (-6600 1800)(-6600 1725);
WIRE 16 -1 (-2200 6350)(-2200 6300);
WIRE 16 -1 (-2200 6300)(-2475 6300);
WIRE 16 -1 (-7625 850)(-7375 850);
WIRE 16 -1 (-7625 900)(-7625 850);
WIRE 17 273 (-9150 225)(-7925 225);
WIRE 17 273 (-9150 650)(-9150 225);
WIRE 17 273 (-7925 650)(-7925 225);
WIRE 17 273 (-9150 650)(-7925 650);
DOT 1 (-6050 5525);
DOT 1 (-5700 5975);
DOT 1 (-5700 6400);
DOT 1 (-3000 6300);
DOT 1 (-3375 6300);
DOT 1 (-3000 5825);
DOT 1 (-3375 5825);
DOT 1 (-2025 1625);
DOT 1 (-2125 1625);
DOT 1 (-3450 925);
DOT 1 (-5700 6125);
DOT 1 (-6050 5225);
DOT 1 (-5750 4075);
DOT 1 (-5750 3825);
DOT 1 (-5375 2725);
DOT 1 (-5975 2125);
DOT 1 (-5400 675);
DOT 1 (-5725 675);
DOT 1 (-6750 4075);
DOT 1 (-6750 3825);
DOT 1 (-6375 4675);
DOT 1 (-6525 850);
DOT 1 (-6950 850);
CIRCLE (-6100 4125)(-5989 4125);
PAINT YELLOW (-6100 4125);
FORCENOTE
TRACE SPACING = 5MIL
(-7850 3425) 0;
DISPLAY LEFT (-7850 3425);
DISPLAY 0.808511 (-7850 3425);
PAINT WHITE (-7850 3425);
FORCENOTE
TRACE WIDTH = 10MIL
(-7850 3500) 0;
DISPLAY LEFT (-7850 3500);
DISPLAY 0.808511 (-7850 3500);
PAINT WHITE (-7850 3500);
FORCENOTE
DIFFERENTIAL PAIR
(-7850 3575) 0;
DISPLAY LEFT (-7850 3575);
DISPLAY 0.808511 (-7850 3575);
PAINT WHITE (-7850 3575);
FORCENOTE
EFFICIENCY > 90% @TDC
(-1725 5825) 0;
DISPLAY LEFT (-1725 5825);
DISPLAY 0.936170 (-1725 5825);
PAINT WHITE (-1725 5825);
FORCENOTE
WORK FREQUENCY=600KHZ
(-1725 5900) 0;
DISPLAY LEFT (-1725 5900);
DISPLAY 0.936170 (-1725 5900);
PAINT WHITE (-1725 5900);
FORCENOTE
MAX LOAD RELEASE=35A
(-1725 5975) 0;
DISPLAY LEFT (-1725 5975);
DISPLAY 0.936170 (-1725 5975);
PAINT WHITE (-1725 5975);
FORCENOTE
MAX LOAD STEP=25A
(-1725 6050) 0;
DISPLAY LEFT (-1725 6050);
DISPLAY 0.936170 (-1725 6050);
PAINT WHITE (-1725 6050);
FORCENOTE
OCP=96A (EDC*1.2)
(-1725 6125) 0;
DISPLAY LEFT (-1725 6125);
DISPLAY 0.936170 (-1725 6125);
PAINT WHITE (-1725 6125);
FORCENOTE
DC & AC=1.045-1.155V
(-1725 6350) 0;
DISPLAY LEFT (-1725 6350);
DISPLAY 0.936170 (-1725 6350);
PAINT WHITE (-1725 6350);
FORCENOTE
OUTPUT VOLTAGE=1.1V
(-1725 6425) 0;
DISPLAY LEFT (-1725 6425);
DISPLAY 0.936170 (-1725 6425);
PAINT WHITE (-1725 6425);
FORCENOTE
PVDD11_S3_P1 SPECFICATION
(-1725 6550) 0;
DISPLAY LEFT (-1725 6550);
DISPLAY 1.276596 (-1725 6550);
PAINT WHITE (-1725 6550);
FORCENOTE
IRM REV1.09
(-1725 5750) 0;
DISPLAY LEFT (-1725 5750);
DISPLAY 0.936170 (-1725 5750);
PAINT WHITE (-1725 5750);
FORCENOTE
PR6 = CS00002JB13
(-2100 3025) 0;
DISPLAY LEFT (-2100 3025);
DISPLAY 1.021277 (-2100 3025);
PAINT WHITE (-2100 3025);
FORCENOTE
PR464 = CS32702FB03
(-2100 2875) 0;
DISPLAY LEFT (-2100 2875);
DISPLAY 1.021277 (-2100 2875);
PAINT WHITE (-2100 2875);
FORCENOTE
PC643 = CH31004KB17
(-2100 2650) 0;
DISPLAY LEFT (-2100 2650);
DISPLAY 1.021277 (-2100 2650);
PAINT WHITE (-2100 2650);
FORCENOTE
PC644=CH5103KEB01
(-2100 2500) 0;
DISPLAY LEFT (-2100 2500);
DISPLAY 1.021277 (-2100 2500);
PAINT WHITE (-2100 2500);
FORCENOTE
PC8 = CH21006JB10
(-2100 2575) 0;
DISPLAY LEFT (-2100 2575);
DISPLAY 1.021277 (-2100 2575);
PAINT WHITE (-2100 2575);
FORCENOTE
PR604 = CS24992FB07
(-2100 2725) 0;
DISPLAY LEFT (-2100 2725);
DISPLAY 1.021277 (-2100 2725);
PAINT WHITE (-2100 2725);
FORCENOTE
PR388 = CS37502FB05
(-2100 2800) 0;
DISPLAY LEFT (-2100 2800);
DISPLAY 1.021277 (-2100 2800);
PAINT WHITE (-2100 2800);
FORCENOTE
PR13,PR14,PR406,PR407,PR408,PR409 = EMPTY
(-2100 2950) 0;
DISPLAY LEFT (-2100 2950);
DISPLAY 1.021277 (-2100 2950);
PAINT WHITE (-2100 2950);
FORCENOTE
PC639,PR376,PC638=EMPTY
(-2100 3100) 0;
DISPLAY LEFT (-2100 3100);
DISPLAY 1.021277 (-2100 3100);
PAINT WHITE (-2100 3100);
FORCENOTE
PU54 = TBD/MP2856GUT-0021-Z
(-2100 3175) 0;
DISPLAY LEFT (-2100 3175);
DISPLAY 1.021277 (-2100 3175);
PAINT WHITE (-2100 3175);
FORCENOTE
PR384 = CS01002FB07
(-2125 3875) 0;
DISPLAY LEFT (-2125 3875);
DISPLAY 1.021277 (-2125 3875);
PAINT WHITE (-2125 3875);
FORCENOTE
PR408,PR409,PR415 = EMPTY
(-2125 3950) 0;
DISPLAY LEFT (-2125 3950);
DISPLAY 1.021277 (-2125 3950);
PAINT WHITE (-2125 3950);
FORCENOTE
PR14,PR13,PR406,PR407 = EMPTY
(-2125 4025) 0;
DISPLAY LEFT (-2125 4025);
DISPLAY 1.021277 (-2125 4025);
PAINT WHITE (-2125 4025);
FORCENOTE
PR6 = CS21002FB06
(-2125 4100) 0;
DISPLAY LEFT (-2125 4100);
DISPLAY 1.021277 (-2125 4100);
PAINT WHITE (-2125 4100);
FORCENOTE
PR376 = CS25362FB02
(-2125 4175) 0;
DISPLAY LEFT (-2125 4175);
DISPLAY 1.021277 (-2125 4175);
PAINT WHITE (-2125 4175);
FORCENOTE
PU54 = TBD/XDPE19283B
(-2125 4250) 0;
DISPLAY LEFT (-2125 4250);
DISPLAY 1.021277 (-2125 4250);
PAINT WHITE (-2125 4250);
FORCENOTE
2ND SOURCE:INFENEON BOM
(-2125 4350) 0;
DISPLAY LEFT (-2125 4350);
DISPLAY 1.276596 (-2125 4350);
PAINT WHITE (-2125 4350);
FORCENOTE
MAIN SOURCE:RENESAS BOM
(-2125 4650) 0;
DISPLAY LEFT (-2125 4650);
DISPLAY 1.276596 (-2125 4650);
PAINT WHITE (-2125 4650);
FORCENOTE
PU54 = TBD/RAA229621GNP#HA0
(-2125 4550) 0;
DISPLAY LEFT (-2125 4550);
DISPLAY 1.021277 (-2125 4550);
PAINT WHITE (-2125 4550);
FORCENOTE
BOM NOTE
(-2125 4800) 0;
DISPLAY LEFT (-2125 4800);
DISPLAY 1.595745 (-2125 4800);
PAINT WHITE (-2125 4800);
FORCENOTE
PR464=CS23572FB05
(-2125 3800) 0;
DISPLAY LEFT (-2125 3800);
DISPLAY 1.021277 (-2125 3800);
PAINT WHITE (-2125 3800);
FORCENOTE
PC644 = CH5103KEB01
(-2125 3725) 0;
DISPLAY LEFT (-2125 3725);
DISPLAY 1.021277 (-2125 3725);
PAINT WHITE (-2125 3725);
FORCENOTE
PC643 = CH11006JB00
(-2125 3650) 0;
DISPLAY LEFT (-2125 3650);
DISPLAY 1.021277 (-2125 3650);
PAINT WHITE (-2125 3650);
FORCENOTE
3RD SOURCE:MPS BOM
(-2125 3275) 0;
DISPLAY LEFT (-2125 3275);
DISPLAY 1.276596 (-2125 3275);
PAINT WHITE (-2125 3275);
FORCENOTE
PC638 = CH3104J1B00
(-2125 3500) 0;
DISPLAY LEFT (-2125 3500);
DISPLAY 1.021277 (-2125 3500);
PAINT WHITE (-2125 3500);
FORCENOTE
PC639 = CH12206KB14
(-2125 3575) 0;
DISPLAY LEFT (-2125 3575);
DISPLAY 1.021277 (-2125 3575);
PAINT WHITE (-2125 3575);
FORCENOTE
EDC=80A
(-1725 6200) 0;
DISPLAY LEFT (-1725 6200);
DISPLAY 0.936170 (-1725 6200);
PAINT WHITE (-1725 6200);
FORCENOTE
TDC=65A
(-1725 6275) 0;
DISPLAY LEFT (-1725 6275);
DISPLAY 0.936170 (-1725 6275);
PAINT WHITE (-1725 6275);
FORCENOTE
VR
(-9075 575) 0;
DISPLAY LEFT (-9075 575);
DISPLAY 0.808511 (-9075 575);
PAINT WHITE (-9075 575);
FORCENOTE
RENESAS
(-9075 475) 0;
DISPLAY LEFT (-9075 475);
DISPLAY 0.638298 (-9075 475);
PAINT WHITE (-9075 475);
FORCENOTE
INFINEON
(-9075 375) 0;
DISPLAY LEFT (-9075 375);
DISPLAY 0.638298 (-9075 375);
PAINT WHITE (-9075 375);
FORCENOTE
MPS
(-9075 275) 0;
DISPLAY LEFT (-9075 275);
DISPLAY 0.638298 (-9075 275);
PAINT WHITE (-9075 275);
FORCENOTE
CONFIG/R
(-8275 575) 0;
DISPLAY LEFT (-8275 575);
DISPLAY 0.808511 (-8275 575);
PAINT WHITE (-8275 575);
FORCENOTE
0/13.7K
(-8275 475) 0;
DISPLAY LEFT (-8275 475);
DISPLAY 0.638298 (-8275 475);
PAINT WHITE (-8275 475);
FORCENOTE
0X4A
(-8625 275) 0;
DISPLAY LEFT (-8625 275);
DISPLAY 0.638298 (-8625 275);
PAINT WHITE (-8625 275);
FORCENOTE
/27K
(-8275 275) 0;
DISPLAY LEFT (-8275 275);
DISPLAY 0.638298 (-8275 275);
PAINT WHITE (-8275 275);
FORCENOTE
/3.57K
(-8275 375) 0;
DISPLAY LEFT (-8275 375);
DISPLAY 0.638298 (-8275 375);
PAINT WHITE (-8275 375);
FORCENOTE
0X4A
(-8625 375) 0;
DISPLAY LEFT (-8625 375);
DISPLAY 0.638298 (-8625 375);
PAINT WHITE (-8625 375);
FORCENOTE
0X75
(-8625 475) 0;
DISPLAY LEFT (-8625 475);
DISPLAY 0.638298 (-8625 475);
PAINT WHITE (-8625 475);
FORCENOTE
ADDRESS(7-BIT)
(-8850 575) 0;
DISPLAY LEFT (-8850 575);
DISPLAY 0.808511 (-8850 575);
PAINT WHITE (-8850 575);
FORCENOTE
PMBUS ADDRESS AND CONFIG
(-9175 700) 0;
DISPLAY LEFT (-9175 700);
DISPLAY 1.170213 (-9175 700);
PAINT WHITE (-9175 700);
QUIT
